FILE_TYPE = MACRO_DRAWING;
SET COLOR_WIRE YELLOW;
SET COLOR_PROP ORANGE;
SET COLOR_DOT WHITE;
SET COLOR_ARC YELLOW;
SET COLOR_BODY GREEN;
SET COLOR_NOTE PURPLE;
SET PROP_DISPLAY VALUE;
SET PAGE_NUMBER P198;
FORCEADD UNIVERSAL_GND..1
(-11525 1600);
FORCEPROP 3 LASTPIN (-11525 1650) SIG_NAME GND\g
J 0
(-11515 1660);
DISPLAY 0.659574 (-11515 1660);
PAINT MONO (-11515 1660);
DISPLAY INVISIBLE (-11515 1660);
FORCEPROP 2 LAST CDS_LIB pure_quanta_power
J 0
(-11525 1600);
PAINT MONO (-11525 1600);
DISPLAY INVISIBLE (-11525 1600);
FORCEPROP 1 LAST PATH I1
J 0
(-11450 1600);
DISPLAY 0.872340 (-11450 1600);
PAINT AQUA (-11450 1600);
DISPLAY INVISIBLE (-11450 1600);
FORCEPROP 1 LAST HDL_POWER GND
J 1
(-11500 1525);
DISPLAY 0.872340 (-11500 1525);
PAINT GREEN (-11500 1525);
DISPLAY INVISIBLE (-11500 1525);
FORCEADD Q_CAP..1
(-8650 6075);
FORCEPROP 1 LAST LOCATION PC622_3
J 0
(-8600 6175);
DISPLAY 0.489362 (-8600 6175);
PAINT SKYBLUE (-8600 6175);
FORCEPROP 0 LAST $SEC 1
J 0
(-8600 6225);
DISPLAY 0.680851 (-8600 6225);
PAINT MONO (-8600 6225);
DISPLAY INVISIBLE (-8600 6225);
FORCEPROP 0 LAST CDS_SEC 1
J 0
(-8600 6225);
DISPLAY 1.021277 (-8600 6225);
DISPLAY INVISIBLE (-8600 6225);
FORCEPROP 1 LASTPIN (-8650 6175) $PN 1
J 0
(-8640 6155);
DISPLAY 0.489362 (-8640 6155);
PAINT MONO (-8640 6155);
FORCEPROP 1 LASTPIN (-8650 5975) $PN 2
J 0
(-8640 5955);
DISPLAY 0.489362 (-8640 5955);
PAINT MONO (-8640 5955);
FORCEPROP 1 LAST MATERIAL X7R
J 0
(-8600 5975);
DISPLAY 0.489362 (-8600 5975);
PAINT SKYBLUE (-8600 5975);
FORCEPROP 1 LAST TOLERANCE 10%
J 0
(-8600 6025);
DISPLAY 0.489362 (-8600 6025);
PAINT SKYBLUE (-8600 6025);
FORCEPROP 1 LAST VALUE 0.1UF
J 0
(-8600 6125);
DISPLAY 0.489362 (-8600 6125);
PAINT SKYBLUE (-8600 6125);
FORCEPROP 1 LAST PART_NUMBER CH4104K1B00
J 0
(-8600 5925);
DISPLAY 0.489362 (-8600 5925);
PAINT SKYBLUE (-8600 5925);
FORCEPROP 1 LAST VOLTAGE 25V
J 0
(-8600 6075);
DISPLAY 0.489362 (-8600 6075);
PAINT SKYBLUE (-8600 6075);
FORCEPROP 1 LAST PACK_TYPE 0402
J 0
(-8600 5875);
DISPLAY 0.489362 (-8600 5875);
PAINT SKYBLUE (-8600 5875);
FORCEPROP 2 LAST CDS_LIB pure_quanta
J 0
(-8650 6075);
DISPLAY INVISIBLE (-8650 6075);
FORCEPROP 1 LAST PATH I100
J 0
(-8600 6225);
DISPLAY 0.978723 (-8600 6225);
PAINT WHITE (-8600 6225);
DISPLAY INVISIBLE (-8600 6225);
FORCEADD Q_CAP..1
(-8625 3300);
FORCEPROP 1 LAST LOCATION PC623_4
J 0
(-8575 3400);
DISPLAY 0.489362 (-8575 3400);
PAINT SKYBLUE (-8575 3400);
FORCEPROP 0 LAST $SEC 1
J 0
(-8575 3450);
DISPLAY 0.680851 (-8575 3450);
PAINT MONO (-8575 3450);
DISPLAY INVISIBLE (-8575 3450);
FORCEPROP 0 LAST CDS_SEC 1
J 0
(-8575 3450);
DISPLAY 1.021277 (-8575 3450);
DISPLAY INVISIBLE (-8575 3450);
FORCEPROP 1 LASTPIN (-8625 3400) $PN 1
J 0
(-8615 3380);
DISPLAY 0.489362 (-8615 3380);
PAINT MONO (-8615 3380);
FORCEPROP 1 LASTPIN (-8625 3200) $PN 2
J 0
(-8615 3180);
DISPLAY 0.489362 (-8615 3180);
PAINT MONO (-8615 3180);
FORCEPROP 1 LAST MATERIAL X7R
J 0
(-8575 3200);
DISPLAY 0.489362 (-8575 3200);
PAINT SKYBLUE (-8575 3200);
FORCEPROP 1 LAST TOLERANCE 10%
J 0
(-8575 3250);
DISPLAY 0.489362 (-8575 3250);
PAINT SKYBLUE (-8575 3250);
FORCEPROP 1 LAST VALUE 0.1UF
J 0
(-8575 3350);
DISPLAY 0.489362 (-8575 3350);
PAINT SKYBLUE (-8575 3350);
FORCEPROP 1 LAST PART_NUMBER CH4104K1B00
J 0
(-8575 3150);
DISPLAY 0.489362 (-8575 3150);
PAINT SKYBLUE (-8575 3150);
FORCEPROP 1 LAST VOLTAGE 25V
J 0
(-8575 3300);
DISPLAY 0.489362 (-8575 3300);
PAINT SKYBLUE (-8575 3300);
FORCEPROP 1 LAST PACK_TYPE 0402
J 0
(-8575 3100);
DISPLAY 0.489362 (-8575 3100);
PAINT SKYBLUE (-8575 3100);
FORCEPROP 2 LAST CDS_LIB pure_quanta
J 0
(-8625 3300);
DISPLAY INVISIBLE (-8625 3300);
FORCEPROP 1 LAST PATH I101
J 0
(-8575 3450);
DISPLAY 0.978723 (-8575 3450);
PAINT WHITE (-8575 3450);
DISPLAY INVISIBLE (-8575 3450);
FORCEADD Q_CAP..1
(-11175 5425);
FORCEPROP 1 LAST LOCATION PC617
J 0
(-11125 5525);
DISPLAY 0.489362 (-11125 5525);
PAINT SKYBLUE (-11125 5525);
FORCEPROP 0 LAST $SEC 1
J 0
(-11125 5575);
DISPLAY 0.680851 (-11125 5575);
PAINT MONO (-11125 5575);
DISPLAY INVISIBLE (-11125 5575);
FORCEPROP 0 LAST CDS_SEC 1
J 0
(-11125 5575);
DISPLAY 1.021277 (-11125 5575);
DISPLAY INVISIBLE (-11125 5575);
FORCEPROP 1 LASTPIN (-11175 5525) $PN 1
J 0
(-11165 5505);
DISPLAY 0.489362 (-11165 5505);
PAINT MONO (-11165 5505);
FORCEPROP 1 LASTPIN (-11175 5325) $PN 2
J 0
(-11165 5305);
DISPLAY 0.489362 (-11165 5305);
PAINT MONO (-11165 5305);
FORCEPROP 1 LAST MATERIAL X6S
J 0
(-11125 5325);
DISPLAY 0.489362 (-11125 5325);
PAINT SKYBLUE (-11125 5325);
FORCEPROP 1 LAST TOLERANCE 10%
J 0
(-11125 5375);
DISPLAY 0.489362 (-11125 5375);
PAINT SKYBLUE (-11125 5375);
FORCEPROP 1 LAST VALUE 2.2UF
J 0
(-11125 5475);
DISPLAY 0.489362 (-11125 5475);
PAINT SKYBLUE (-11125 5475);
FORCEPROP 1 LAST PART_NUMBER CH5222KEB01
J 0
(-11125 5275);
DISPLAY 0.489362 (-11125 5275);
PAINT SKYBLUE (-11125 5275);
FORCEPROP 1 LAST VOLTAGE 10V
J 0
(-11125 5425);
DISPLAY 0.489362 (-11125 5425);
PAINT SKYBLUE (-11125 5425);
FORCEPROP 1 LAST PACK_TYPE C0402
J 0
(-11125 5225);
DISPLAY 0.489362 (-11125 5225);
PAINT SKYBLUE (-11125 5225);
FORCEPROP 2 LAST CDS_LIB pure_quanta
J 0
(-11175 5425);
DISPLAY INVISIBLE (-11175 5425);
FORCEPROP 1 LAST PATH I102
J 0
(-11125 5575);
DISPLAY 0.978723 (-11125 5575);
PAINT WHITE (-11125 5575);
DISPLAY INVISIBLE (-11125 5575);
FORCEADD UNIVERSAL_GND..1
(-11175 5225);
FORCEPROP 3 LASTPIN (-11175 5275) SIG_NAME GND\g
J 0
(-11165 5285);
DISPLAY 0.659574 (-11165 5285);
PAINT MONO (-11165 5285);
DISPLAY INVISIBLE (-11165 5285);
FORCEPROP 2 LAST CDS_LIB pure_quanta_power
J 0
(-11175 5225);
DISPLAY INVISIBLE (-11175 5225);
FORCEPROP 1 LAST PATH I103
J 0
(-11100 5225);
DISPLAY 0.872340 (-11100 5225);
PAINT AQUA (-11100 5225);
DISPLAY INVISIBLE (-11100 5225);
FORCEPROP 1 LAST HDL_POWER GND
J 1
(-11150 5150);
DISPLAY 0.872340 (-11150 5150);
PAINT GREEN (-11150 5150);
DISPLAY INVISIBLE (-11150 5150);
FORCEADD UNIVERSAL_GND..1
(-10825 5725);
FORCEPROP 3 LASTPIN (-10825 5775) SIG_NAME GND\g
J 0
(-10815 5785);
DISPLAY 0.659574 (-10815 5785);
PAINT MONO (-10815 5785);
DISPLAY INVISIBLE (-10815 5785);
FORCEPROP 2 LAST CDS_LIB pure_quanta_power
J 0
(-10825 5725);
DISPLAY INVISIBLE (-10825 5725);
FORCEPROP 1 LAST PATH I104
J 0
(-10750 5725);
DISPLAY 0.872340 (-10750 5725);
PAINT AQUA (-10750 5725);
DISPLAY INVISIBLE (-10750 5725);
FORCEPROP 1 LAST HDL_POWER GND
J 1
(-10800 5650);
DISPLAY 0.872340 (-10800 5650);
PAINT GREEN (-10800 5650);
DISPLAY INVISIBLE (-10800 5650);
FORCEADD Q_RES..2
(-11175 5975);
FORCEPROP 1 LAST LOCATION PR371
J 0
(-11130 6100);
DISPLAY 0.489362 (-11130 6100);
PAINT SKYBLUE (-11130 6100);
FORCEPROP 0 LAST $SEC 1
J 0
(-11125 6150);
DISPLAY 0.680851 (-11125 6150);
PAINT MONO (-11125 6150);
DISPLAY INVISIBLE (-11125 6150);
FORCEPROP 0 LAST CDS_SEC 1
J 0
(-11125 6150);
DISPLAY 1.021277 (-11125 6150);
DISPLAY INVISIBLE (-11125 6150);
FORCEPROP 1 LASTPIN (-11175 6075) $PN 1
J 0
(-11170 6037);
DISPLAY 0.489362 (-11170 6037);
PAINT MONO (-11170 6037);
FORCEPROP 1 LASTPIN (-11175 5875) $PN 2
J 0
(-11170 5885);
DISPLAY 0.489362 (-11170 5885);
PAINT MONO (-11170 5885);
FORCEPROP 1 LAST WATTAGE 1/16W
J 0
(-11125 5950);
DISPLAY 0.489362 (-11125 5950);
PAINT SKYBLUE (-11125 5950);
FORCEPROP 1 LAST MATERIAL CHIP
J 0
(-11125 5900);
DISPLAY 0.489362 (-11125 5900);
PAINT SKYBLUE (-11125 5900);
FORCEPROP 1 LAST TOLERANCE 1%
J 0
(-11125 6000);
DISPLAY 0.489362 (-11125 6000);
PAINT SKYBLUE (-11125 6000);
FORCEPROP 1 LAST VALUE 2.2
J 0
(-11125 6050);
DISPLAY 0.489362 (-11125 6050);
PAINT SKYBLUE (-11125 6050);
FORCEPROP 1 LAST PART_NUMBER CS-2202FB00
J 0
(-11125 5850);
DISPLAY 0.489362 (-11125 5850);
PAINT SKYBLUE (-11125 5850);
FORCEPROP 1 LAST PACK_TYPE 0402LF
J 0
(-11125 5800);
DISPLAY 0.489362 (-11125 5800);
PAINT SKYBLUE (-11125 5800);
FORCEPROP 2 LAST CDS_LIB pure_quanta
J 0
(-11175 5975);
DISPLAY INVISIBLE (-11175 5975);
FORCEPROP 1 LAST PATH I105
J 0
(-11125 6150);
DISPLAY 0.978723 (-11125 6150);
PAINT WHITE (-11125 6150);
DISPLAY INVISIBLE (-11125 6150);
FORCEADD Q_CAP..1
(-10825 6000);
FORCEPROP 1 LAST LOCATION PC619_IOP1_3
J 0
(-10775 6100);
DISPLAY 0.489362 (-10775 6100);
PAINT SKYBLUE (-10775 6100);
FORCEPROP 0 LAST $SEC 1
J 0
(-10775 6150);
DISPLAY 0.680851 (-10775 6150);
PAINT MONO (-10775 6150);
DISPLAY INVISIBLE (-10775 6150);
FORCEPROP 0 LAST CDS_SEC 1
J 0
(-10775 6150);
DISPLAY 1.021277 (-10775 6150);
DISPLAY INVISIBLE (-10775 6150);
FORCEPROP 1 LASTPIN (-10825 6100) $PN 1
J 0
(-10815 6080);
DISPLAY 0.489362 (-10815 6080);
PAINT MONO (-10815 6080);
FORCEPROP 1 LASTPIN (-10825 5900) $PN 2
J 0
(-10815 5880);
DISPLAY 0.489362 (-10815 5880);
PAINT MONO (-10815 5880);
FORCEPROP 1 LAST MATERIAL X6S
J 0
(-10775 5900);
DISPLAY 0.489362 (-10775 5900);
PAINT SKYBLUE (-10775 5900);
FORCEPROP 1 LAST TOLERANCE 10%
J 0
(-10775 5950);
DISPLAY 0.489362 (-10775 5950);
PAINT SKYBLUE (-10775 5950);
FORCEPROP 1 LAST VALUE 2.2UF
J 0
(-10775 6050);
DISPLAY 0.489362 (-10775 6050);
PAINT SKYBLUE (-10775 6050);
FORCEPROP 1 LAST PART_NUMBER CH5222KEB01
J 0
(-10775 5850);
DISPLAY 0.489362 (-10775 5850);
PAINT SKYBLUE (-10775 5850);
FORCEPROP 1 LAST VOLTAGE 10V
J 0
(-10775 6000);
DISPLAY 0.489362 (-10775 6000);
PAINT SKYBLUE (-10775 6000);
FORCEPROP 1 LAST PACK_TYPE C0402
J 0
(-10775 5800);
DISPLAY 0.489362 (-10775 5800);
PAINT SKYBLUE (-10775 5800);
FORCEPROP 2 LAST CDS_LIB pure_quanta
J 0
(-10825 6000);
DISPLAY INVISIBLE (-10825 6000);
FORCEPROP 1 LAST PATH I106
J 0
(-10775 6150);
DISPLAY 0.978723 (-10775 6150);
PAINT WHITE (-10775 6150);
DISPLAY INVISIBLE (-10775 6150);
FORCEADD Q_CAP..1
(-11200 2725);
FORCEPROP 1 LAST LOCATION PC616
J 0
(-11150 2825);
DISPLAY 0.489362 (-11150 2825);
PAINT SKYBLUE (-11150 2825);
FORCEPROP 0 LAST $SEC 1
J 0
(-11150 2875);
DISPLAY 0.680851 (-11150 2875);
PAINT MONO (-11150 2875);
DISPLAY INVISIBLE (-11150 2875);
FORCEPROP 0 LAST CDS_SEC 1
J 0
(-11150 2875);
DISPLAY 1.021277 (-11150 2875);
DISPLAY INVISIBLE (-11150 2875);
FORCEPROP 1 LASTPIN (-11200 2825) $PN 1
J 0
(-11190 2805);
DISPLAY 0.489362 (-11190 2805);
PAINT MONO (-11190 2805);
FORCEPROP 1 LASTPIN (-11200 2625) $PN 2
J 0
(-11190 2605);
DISPLAY 0.489362 (-11190 2605);
PAINT MONO (-11190 2605);
FORCEPROP 1 LAST MATERIAL X6S
J 0
(-11150 2625);
DISPLAY 0.489362 (-11150 2625);
PAINT SKYBLUE (-11150 2625);
FORCEPROP 1 LAST TOLERANCE 10%
J 0
(-11150 2675);
DISPLAY 0.489362 (-11150 2675);
PAINT SKYBLUE (-11150 2675);
FORCEPROP 1 LAST VALUE 2.2UF
J 0
(-11150 2775);
DISPLAY 0.489362 (-11150 2775);
PAINT SKYBLUE (-11150 2775);
FORCEPROP 1 LAST PART_NUMBER CH5222KEB01
J 0
(-11150 2575);
DISPLAY 0.489362 (-11150 2575);
PAINT SKYBLUE (-11150 2575);
FORCEPROP 1 LAST VOLTAGE 10V
J 0
(-11150 2725);
DISPLAY 0.489362 (-11150 2725);
PAINT SKYBLUE (-11150 2725);
FORCEPROP 1 LAST PACK_TYPE C0402
J 0
(-11150 2525);
DISPLAY 0.489362 (-11150 2525);
PAINT SKYBLUE (-11150 2525);
FORCEPROP 2 LAST CDS_LIB pure_quanta
J 0
(-11200 2725);
DISPLAY INVISIBLE (-11200 2725);
FORCEPROP 1 LAST PATH I108
J 0
(-11150 2875);
DISPLAY 0.978723 (-11150 2875);
PAINT WHITE (-11150 2875);
DISPLAY INVISIBLE (-11150 2875);
FORCEADD UNIVERSAL_GND..1
(-11200 2525);
FORCEPROP 3 LASTPIN (-11200 2575) SIG_NAME GND\g
J 0
(-11190 2585);
DISPLAY 0.659574 (-11190 2585);
PAINT MONO (-11190 2585);
DISPLAY INVISIBLE (-11190 2585);
FORCEPROP 2 LAST CDS_LIB pure_quanta_power
J 0
(-11200 2525);
DISPLAY INVISIBLE (-11200 2525);
FORCEPROP 1 LAST PATH I109
J 0
(-11125 2525);
DISPLAY 0.872340 (-11125 2525);
PAINT AQUA (-11125 2525);
DISPLAY INVISIBLE (-11125 2525);
FORCEPROP 1 LAST HDL_POWER GND
J 1
(-11175 2450);
DISPLAY 0.872340 (-11175 2450);
PAINT GREEN (-11175 2450);
DISPLAY INVISIBLE (-11175 2450);
FORCEADD UNIVERSAL_GND..1
(-10850 3025);
FORCEPROP 3 LASTPIN (-10850 3075) SIG_NAME GND\g
J 0
(-10840 3085);
DISPLAY 0.659574 (-10840 3085);
PAINT MONO (-10840 3085);
DISPLAY INVISIBLE (-10840 3085);
FORCEPROP 2 LAST CDS_LIB pure_quanta_power
J 0
(-10850 3025);
DISPLAY INVISIBLE (-10850 3025);
FORCEPROP 1 LAST PATH I110
J 0
(-10775 3025);
DISPLAY 0.872340 (-10775 3025);
PAINT AQUA (-10775 3025);
DISPLAY INVISIBLE (-10775 3025);
FORCEPROP 1 LAST HDL_POWER GND
J 1
(-10825 2950);
DISPLAY 0.872340 (-10825 2950);
PAINT GREEN (-10825 2950);
DISPLAY INVISIBLE (-10825 2950);
FORCEADD Q_RES..2
(-11200 3275);
FORCEPROP 1 LAST LOCATION PR370
J 0
(-11155 3400);
DISPLAY 0.489362 (-11155 3400);
PAINT SKYBLUE (-11155 3400);
FORCEPROP 0 LAST $SEC 1
J 0
(-11150 3450);
DISPLAY 0.680851 (-11150 3450);
PAINT MONO (-11150 3450);
DISPLAY INVISIBLE (-11150 3450);
FORCEPROP 0 LAST CDS_SEC 1
J 0
(-11150 3450);
DISPLAY 1.021277 (-11150 3450);
DISPLAY INVISIBLE (-11150 3450);
FORCEPROP 1 LASTPIN (-11200 3375) $PN 1
J 0
(-11195 3337);
DISPLAY 0.489362 (-11195 3337);
PAINT MONO (-11195 3337);
FORCEPROP 1 LASTPIN (-11200 3175) $PN 2
J 0
(-11195 3185);
DISPLAY 0.489362 (-11195 3185);
PAINT MONO (-11195 3185);
FORCEPROP 1 LAST WATTAGE 1/16W
J 0
(-11150 3250);
DISPLAY 0.489362 (-11150 3250);
PAINT SKYBLUE (-11150 3250);
FORCEPROP 1 LAST MATERIAL CHIP
J 0
(-11150 3200);
DISPLAY 0.489362 (-11150 3200);
PAINT SKYBLUE (-11150 3200);
FORCEPROP 1 LAST TOLERANCE 1%
J 0
(-11150 3300);
DISPLAY 0.489362 (-11150 3300);
PAINT SKYBLUE (-11150 3300);
FORCEPROP 1 LAST VALUE 2.2
J 0
(-11150 3350);
DISPLAY 0.489362 (-11150 3350);
PAINT SKYBLUE (-11150 3350);
FORCEPROP 1 LAST PART_NUMBER CS-2202FB00
J 0
(-11150 3150);
DISPLAY 0.489362 (-11150 3150);
PAINT SKYBLUE (-11150 3150);
FORCEPROP 1 LAST PACK_TYPE 0402LF
J 0
(-11150 3100);
DISPLAY 0.489362 (-11150 3100);
PAINT SKYBLUE (-11150 3100);
FORCEPROP 2 LAST CDS_LIB pure_quanta
J 0
(-11200 3275);
DISPLAY INVISIBLE (-11200 3275);
FORCEPROP 1 LAST PATH I111
J 0
(-11150 3450);
DISPLAY 0.978723 (-11150 3450);
PAINT WHITE (-11150 3450);
DISPLAY INVISIBLE (-11150 3450);
FORCEADD Q_CAP..1
(-10850 3300);
FORCEPROP 1 LAST LOCATION PC618_IOP1_4
J 0
(-10800 3400);
DISPLAY 0.489362 (-10800 3400);
PAINT SKYBLUE (-10800 3400);
FORCEPROP 0 LAST $SEC 1
J 0
(-10800 3450);
DISPLAY 0.680851 (-10800 3450);
PAINT MONO (-10800 3450);
DISPLAY INVISIBLE (-10800 3450);
FORCEPROP 0 LAST CDS_SEC 1
J 0
(-10800 3450);
DISPLAY 1.021277 (-10800 3450);
DISPLAY INVISIBLE (-10800 3450);
FORCEPROP 1 LASTPIN (-10850 3400) $PN 1
J 0
(-10840 3380);
DISPLAY 0.489362 (-10840 3380);
PAINT MONO (-10840 3380);
FORCEPROP 1 LASTPIN (-10850 3200) $PN 2
J 0
(-10840 3180);
DISPLAY 0.489362 (-10840 3180);
PAINT MONO (-10840 3180);
FORCEPROP 1 LAST MATERIAL X6S
J 0
(-10800 3200);
DISPLAY 0.489362 (-10800 3200);
PAINT SKYBLUE (-10800 3200);
FORCEPROP 1 LAST TOLERANCE 10%
J 0
(-10800 3250);
DISPLAY 0.489362 (-10800 3250);
PAINT SKYBLUE (-10800 3250);
FORCEPROP 1 LAST VALUE 2.2UF
J 0
(-10800 3350);
DISPLAY 0.489362 (-10800 3350);
PAINT SKYBLUE (-10800 3350);
FORCEPROP 1 LAST PART_NUMBER CH5222KEB01
J 0
(-10800 3150);
DISPLAY 0.489362 (-10800 3150);
PAINT SKYBLUE (-10800 3150);
FORCEPROP 1 LAST VOLTAGE 10V
J 0
(-10800 3300);
DISPLAY 0.489362 (-10800 3300);
PAINT SKYBLUE (-10800 3300);
FORCEPROP 1 LAST PACK_TYPE C0402
J 0
(-10800 3100);
DISPLAY 0.489362 (-10800 3100);
PAINT SKYBLUE (-10800 3100);
FORCEPROP 2 LAST CDS_LIB pure_quanta
J 0
(-10850 3300);
DISPLAY INVISIBLE (-10850 3300);
FORCEPROP 1 LAST PATH I112
J 0
(-10800 3450);
DISPLAY 0.978723 (-10800 3450);
PAINT WHITE (-10800 3450);
DISPLAY INVISIBLE (-10800 3450);
FORCEADD UNIVERSAL_GND..1
(-12050 4550);
FORCEPROP 3 LASTPIN (-12050 4600) SIG_NAME GND\g
J 0
(-12040 4610);
DISPLAY 0.659574 (-12040 4610);
PAINT MONO (-12040 4610);
DISPLAY INVISIBLE (-12040 4610);
FORCEPROP 2 LAST CDS_LIB pure_quanta_power
J 0
(-12050 4550);
DISPLAY INVISIBLE (-12050 4550);
FORCEPROP 1 LAST PATH I114
J 0
(-11975 4550);
DISPLAY 0.872340 (-11975 4550);
PAINT AQUA (-11975 4550);
DISPLAY INVISIBLE (-11975 4550);
FORCEPROP 1 LAST HDL_POWER GND
J 1
(-12025 4475);
DISPLAY 0.872340 (-12025 4475);
PAINT GREEN (-12025 4475);
DISPLAY INVISIBLE (-12025 4475);
FORCEADD UNIVERSAL_GND..1
(-12075 1750);
FORCEPROP 3 LASTPIN (-12075 1800) SIG_NAME GND\g
J 0
(-12065 1810);
DISPLAY 0.659574 (-12065 1810);
PAINT MONO (-12065 1810);
DISPLAY INVISIBLE (-12065 1810);
FORCEPROP 2 LAST CDS_LIB pure_quanta_power
J 0
(-12075 1750);
DISPLAY INVISIBLE (-12075 1750);
FORCEPROP 1 LAST PATH I115
J 0
(-12000 1750);
DISPLAY 0.872340 (-12000 1750);
PAINT AQUA (-12000 1750);
DISPLAY INVISIBLE (-12000 1750);
FORCEPROP 1 LAST HDL_POWER GND
J 1
(-12050 1675);
DISPLAY 0.872340 (-12050 1675);
PAINT GREEN (-12050 1675);
DISPLAY INVISIBLE (-12050 1675);
FORCEADD UNIVERSAL_GND..1
(-8075 4200);
FORCEPROP 3 LASTPIN (-8075 4250) SIG_NAME GND\g
J 0
(-8065 4260);
DISPLAY 0.659574 (-8065 4260);
PAINT MONO (-8065 4260);
DISPLAY INVISIBLE (-8065 4260);
FORCEPROP 2 LAST CDS_LIB pure_quanta_power
J 0
(-8075 4200);
DISPLAY INVISIBLE (-8075 4200);
FORCEPROP 1 LAST PATH I117
J 0
(-8000 4200);
DISPLAY 0.872340 (-8000 4200);
PAINT AQUA (-8000 4200);
DISPLAY INVISIBLE (-8000 4200);
FORCEPROP 1 LAST HDL_POWER GND
J 1
(-8050 4125);
DISPLAY 0.872340 (-8050 4125);
PAINT GREEN (-8050 4125);
DISPLAY INVISIBLE (-8050 4125);
FORCEADD Q_RES..2
(-8075 4425);
FORCEPROP 1 LAST LOCATION PR492
J 0
(-8030 4550);
DISPLAY 0.489362 (-8030 4550);
PAINT SKYBLUE (-8030 4550);
FORCEPROP 0 LAST $SEC 1
J 0
(-8025 4600);
DISPLAY 0.680851 (-8025 4600);
PAINT MONO (-8025 4600);
DISPLAY INVISIBLE (-8025 4600);
FORCEPROP 0 LAST CDS_SEC 1
J 0
(-8025 4600);
DISPLAY 1.021277 (-8025 4600);
DISPLAY INVISIBLE (-8025 4600);
FORCEPROP 1 LASTPIN (-8075 4525) $PN 1
J 0
(-8070 4487);
DISPLAY 0.489362 (-8070 4487);
PAINT MONO (-8070 4487);
FORCEPROP 1 LASTPIN (-8075 4325) $PN 2
J 0
(-8070 4335);
DISPLAY 0.489362 (-8070 4335);
PAINT MONO (-8070 4335);
FORCEPROP 1 LAST WATTAGE 1/8W
J 0
(-8035 4400);
DISPLAY 0.489362 (-8035 4400);
PAINT SKYBLUE (-8035 4400);
FORCEPROP 1 LAST MATERIAL EMPTY
J 0
(-8035 4350);
DISPLAY 0.489362 (-8035 4350);
PAINT RED (-8035 4350);
FORCEPROP 1 LAST TOLERANCE 1%
J 0
(-8030 4450);
DISPLAY 0.489362 (-8030 4450);
PAINT SKYBLUE (-8030 4450);
FORCEPROP 1 LAST VALUE 1.5
J 0
(-8030 4500);
DISPLAY 0.489362 (-8030 4500);
PAINT SKYBLUE (-8030 4500);
FORCEPROP 1 LAST PART_NUMBER CS-1504FB00
J 0
(-8035 4300);
DISPLAY 0.489362 (-8035 4300);
PAINT SKYBLUE (-8035 4300);
FORCEPROP 1 LAST PACK_TYPE 0402LF
J 0
(-8035 4250);
DISPLAY 0.489362 (-8035 4250);
PAINT SKYBLUE (-8035 4250);
FORCEPROP 2 LAST CDS_LIB pure_quanta
J 0
(-8075 4425);
DISPLAY INVISIBLE (-8075 4425);
FORCEPROP 1 LAST PATH I118
J 0
(-8025 4600);
DISPLAY 0.978723 (-8025 4600);
PAINT WHITE (-8025 4600);
DISPLAY INVISIBLE (-8025 4600);
FORCEADD Q_CAP..1
(-8075 4925);
FORCEPROP 1 LAST LOCATION PC177
J 0
(-8025 5025);
DISPLAY 0.489362 (-8025 5025);
PAINT SKYBLUE (-8025 5025);
FORCEPROP 0 LAST $SEC 1
J 0
(-8025 5075);
DISPLAY 0.680851 (-8025 5075);
PAINT MONO (-8025 5075);
DISPLAY INVISIBLE (-8025 5075);
FORCEPROP 0 LAST CDS_SEC 1
J 0
(-8025 5075);
DISPLAY 1.021277 (-8025 5075);
DISPLAY INVISIBLE (-8025 5075);
FORCEPROP 1 LASTPIN (-8075 5025) $PN 1
J 0
(-8065 5005);
DISPLAY 0.489362 (-8065 5005);
PAINT MONO (-8065 5005);
FORCEPROP 1 LASTPIN (-8075 4825) $PN 2
J 0
(-8065 4805);
DISPLAY 0.489362 (-8065 4805);
PAINT MONO (-8065 4805);
FORCEPROP 1 LAST MATERIAL EMPTY
J 0
(-8025 4825);
DISPLAY 0.489362 (-8025 4825);
PAINT RED (-8025 4825);
FORCEPROP 1 LAST TOLERANCE 10%
J 0
(-8025 4875);
DISPLAY 0.489362 (-8025 4875);
PAINT SKYBLUE (-8025 4875);
FORCEPROP 1 LAST VALUE 560PF
J 0
(-8025 4975);
DISPLAY 0.489362 (-8025 4975);
PAINT SKYBLUE (-8025 4975);
FORCEPROP 1 LAST PART_NUMBER CH1566K1B09
J 0
(-8025 4775);
DISPLAY 0.489362 (-8025 4775);
PAINT SKYBLUE (-8025 4775);
FORCEPROP 1 LAST VOLTAGE 50V
J 0
(-8025 4925);
DISPLAY 0.489362 (-8025 4925);
PAINT SKYBLUE (-8025 4925);
FORCEPROP 1 LAST PACK_TYPE C0402
J 0
(-8025 4725);
DISPLAY 0.489362 (-8025 4725);
PAINT SKYBLUE (-8025 4725);
FORCEPROP 2 LAST CDS_LIB pure_quanta
J 0
(-8075 4925);
DISPLAY INVISIBLE (-8075 4925);
FORCEPROP 1 LAST PATH I119
J 0
(-8025 5075);
DISPLAY 0.978723 (-8025 5075);
PAINT WHITE (-8025 5075);
DISPLAY INVISIBLE (-8025 5075);
FORCEADD UNIVERSAL_GND..1
(-8175 1400);
FORCEPROP 3 LASTPIN (-8175 1450) SIG_NAME GND\g
J 0
(-8165 1460);
DISPLAY 0.659574 (-8165 1460);
PAINT MONO (-8165 1460);
DISPLAY INVISIBLE (-8165 1460);
FORCEPROP 2 LAST CDS_LIB pure_quanta_power
J 0
(-8175 1400);
DISPLAY INVISIBLE (-8175 1400);
FORCEPROP 1 LAST PATH I120
J 0
(-8100 1400);
DISPLAY 0.872340 (-8100 1400);
PAINT AQUA (-8100 1400);
DISPLAY INVISIBLE (-8100 1400);
FORCEPROP 1 LAST HDL_POWER GND
J 1
(-8150 1325);
DISPLAY 0.872340 (-8150 1325);
PAINT GREEN (-8150 1325);
DISPLAY INVISIBLE (-8150 1325);
FORCEADD Q_RES..2
(-8175 1625);
FORCEPROP 1 LAST LOCATION PR491
J 0
(-8130 1750);
DISPLAY 0.489362 (-8130 1750);
PAINT SKYBLUE (-8130 1750);
FORCEPROP 0 LAST $SEC 1
J 0
(-8125 1800);
DISPLAY 0.680851 (-8125 1800);
PAINT MONO (-8125 1800);
DISPLAY INVISIBLE (-8125 1800);
FORCEPROP 0 LAST CDS_SEC 1
J 0
(-8125 1800);
DISPLAY 1.021277 (-8125 1800);
DISPLAY INVISIBLE (-8125 1800);
FORCEPROP 1 LASTPIN (-8175 1725) $PN 1
J 0
(-8170 1687);
DISPLAY 0.489362 (-8170 1687);
PAINT MONO (-8170 1687);
FORCEPROP 1 LASTPIN (-8175 1525) $PN 2
J 0
(-8170 1535);
DISPLAY 0.489362 (-8170 1535);
PAINT MONO (-8170 1535);
FORCEPROP 1 LAST WATTAGE 1/8W
J 0
(-8135 1600);
DISPLAY 0.489362 (-8135 1600);
PAINT SKYBLUE (-8135 1600);
FORCEPROP 1 LAST MATERIAL EMPTY
J 0
(-8135 1550);
DISPLAY 0.489362 (-8135 1550);
PAINT RED (-8135 1550);
FORCEPROP 1 LAST TOLERANCE 1%
J 0
(-8130 1650);
DISPLAY 0.489362 (-8130 1650);
PAINT SKYBLUE (-8130 1650);
FORCEPROP 1 LAST VALUE 1.5
J 0
(-8130 1700);
DISPLAY 0.489362 (-8130 1700);
PAINT SKYBLUE (-8130 1700);
FORCEPROP 1 LAST PART_NUMBER CS-1504FB00
J 0
(-8135 1500);
DISPLAY 0.489362 (-8135 1500);
PAINT SKYBLUE (-8135 1500);
FORCEPROP 1 LAST PACK_TYPE 0402LF
J 0
(-8135 1450);
DISPLAY 0.489362 (-8135 1450);
PAINT SKYBLUE (-8135 1450);
FORCEPROP 2 LAST CDS_LIB pure_quanta
J 0
(-8175 1625);
DISPLAY INVISIBLE (-8175 1625);
FORCEPROP 1 LAST PATH I121
J 0
(-8125 1800);
DISPLAY 0.978723 (-8125 1800);
PAINT WHITE (-8125 1800);
DISPLAY INVISIBLE (-8125 1800);
FORCEADD Q_CAP..1
(-8175 2125);
FORCEPROP 1 LAST LOCATION PC176
J 0
(-8125 2225);
DISPLAY 0.489362 (-8125 2225);
PAINT SKYBLUE (-8125 2225);
FORCEPROP 0 LAST $SEC 1
J 0
(-8125 2275);
DISPLAY 0.680851 (-8125 2275);
PAINT MONO (-8125 2275);
DISPLAY INVISIBLE (-8125 2275);
FORCEPROP 0 LAST CDS_SEC 1
J 0
(-8125 2275);
DISPLAY 1.021277 (-8125 2275);
DISPLAY INVISIBLE (-8125 2275);
FORCEPROP 1 LASTPIN (-8175 2225) $PN 1
J 0
(-8165 2205);
DISPLAY 0.489362 (-8165 2205);
PAINT MONO (-8165 2205);
FORCEPROP 1 LASTPIN (-8175 2025) $PN 2
J 0
(-8165 2005);
DISPLAY 0.489362 (-8165 2005);
PAINT MONO (-8165 2005);
FORCEPROP 1 LAST TOLERANCE 10%
J 0
(-8125 2075);
DISPLAY 0.489362 (-8125 2075);
PAINT SKYBLUE (-8125 2075);
FORCEPROP 1 LAST VALUE 560PF
J 0
(-8125 2175);
DISPLAY 0.489362 (-8125 2175);
PAINT SKYBLUE (-8125 2175);
FORCEPROP 1 LAST PACK_TYPE C0402
J 0
(-8125 1925);
DISPLAY 0.489362 (-8125 1925);
PAINT SKYBLUE (-8125 1925);
FORCEPROP 1 LAST VOLTAGE 50V
J 0
(-8125 2125);
DISPLAY 0.489362 (-8125 2125);
PAINT SKYBLUE (-8125 2125);
FORCEPROP 1 LAST PART_NUMBER CH1566K1B09
J 0
(-8125 1975);
DISPLAY 0.489362 (-8125 1975);
PAINT SKYBLUE (-8125 1975);
FORCEPROP 1 LAST MATERIAL EMPTY
J 0
(-8125 2025);
DISPLAY 0.489362 (-8125 2025);
PAINT RED (-8125 2025);
FORCEPROP 2 LAST CDS_LIB pure_quanta
J 0
(-8175 2125);
DISPLAY INVISIBLE (-8175 2125);
FORCEPROP 1 LAST PATH I122
J 0
(-8125 2275);
DISPLAY 0.978723 (-8125 2275);
PAINT WHITE (-8125 2275);
DISPLAY INVISIBLE (-8125 2275);
FORCEADD VCC_CORE..1
(-11175 6375);
FORCEPROP 3 LASTPIN (-11175 6325) SIG_NAME PVDDCR_CPU1_P1_PVCC\g
J 0
(-11165 6335);
DISPLAY 0.659574 (-11165 6335);
PAINT MONO (-11165 6335);
DISPLAY INVISIBLE (-11165 6335);
FORCEPROP 1 LAST HDL_POWER PVDDCR_CPU1_P1_PVCC
J 1
(-11175 6425);
DISPLAY 0.489362 (-11175 6425);
PAINT GREEN (-11175 6425);
FORCEPROP 2 LAST CDS_LIB pure_quanta_power
J 0
(-11175 6375);
DISPLAY INVISIBLE (-11175 6375);
FORCEPROP 1 LAST PATH I123
J 0
(-11125 6400);
DISPLAY 0.872340 (-11125 6400);
PAINT AQUA (-11125 6400);
DISPLAY INVISIBLE (-11125 6400);
FORCEADD VCC_CORE..1
(-11200 3675);
FORCEPROP 3 LASTPIN (-11200 3625) SIG_NAME PVDDCR_CPU1_P1_PVCC\g
J 0
(-11190 3635);
DISPLAY 0.659574 (-11190 3635);
PAINT MONO (-11190 3635);
DISPLAY INVISIBLE (-11190 3635);
FORCEPROP 1 LAST HDL_POWER PVDDCR_CPU1_P1_PVCC
J 1
(-11200 3725);
DISPLAY 0.489362 (-11200 3725);
PAINT GREEN (-11200 3725);
FORCEPROP 2 LAST CDS_LIB pure_quanta_power
J 0
(-11200 3675);
DISPLAY INVISIBLE (-11200 3675);
FORCEPROP 1 LAST PATH I124
J 0
(-11150 3700);
DISPLAY 0.872340 (-11150 3700);
PAINT AQUA (-11150 3700);
DISPLAY INVISIBLE (-11150 3700);
FORCEADD OFFPAGE..3
(-5475 2075);
FORCEPROP 2 LAST $XR0 199 
J 0
(-5261 2075);
DISPLAY 0.638298 (-5261 2075);
PAINT MONO (-5261 2075);
FORCEPROP 2 LAST PATH I127
J 0
(-5275 2100);
DISPLAY 1.021277 (-5275 2100);
DISPLAY INVISIBLE (-5275 2100);
FORCEPROP 2 LAST CDS_LIB standard
J 0
(-5475 2075);
DISPLAY INVISIBLE (-5475 2075);
FORCEPROP 1 LAST OFFPAGE TRUE
J 0
(-5150 1950);
DISPLAY 0.872340 (-5150 1950);
PAINT GREEN (-5150 1950);
DISPLAY INVISIBLE (-5150 1950);
FORCEPROP 1 LAST COMMENT_BODY TRUE
J 0
(-5525 1975);
DISPLAY 0.872340 (-5525 1975);
PAINT GREEN (-5525 1975);
DISPLAY INVISIBLE (-5525 1975);
FORCEADD Q_INDUCTOR..1
R 2
(-7450 2100);
FORCEPROP 1 LAST LOCATION PL46
J 2
(-7500 2250);
DISPLAY 0.468085 (-7500 2250);
PAINT SKYBLUE (-7500 2250);
FORCEPROP 0 LAST $SEC 1
J 0
(-7500 2275);
DISPLAY 0.680851 (-7500 2275);
PAINT MONO (-7500 2275);
DISPLAY INVISIBLE (-7500 2275);
FORCEPROP 0 LAST CDS_SEC 1
J 0
(-7650 2275);
DISPLAY 1.021277 (-7650 2275);
DISPLAY INVISIBLE (-7650 2275);
FORCEPROP 0 LASTPIN (-7350 2075) $PN 1
J 0
(-7340 2085);
DISPLAY 0.680851 (-7340 2085);
PAINT MONO (-7340 2085);
FORCEPROP 0 LASTPIN (-7550 2075) $PN 2
J 2
(-7560 2085);
DISPLAY 0.680851 (-7560 2085);
PAINT MONO (-7560 2085);
FORCEPROP 1 LAST MATERIAL IND
J 2
(-7500 2150);
DISPLAY 0.468085 (-7500 2150);
PAINT SKYBLUE (-7500 2150);
FORCEPROP 1 LAST PART_NUMBER CV+22Y0EZ00
J 2
(-7325 2175);
DISPLAY 0.468085 (-7325 2175);
PAINT SKYBLUE (-7325 2175);
FORCEPROP 2 LAST VALUE 0.22UH/33A
J 0
(-7575 2200);
DISPLAY 0.489362 (-7575 2200);
PAINT SKYBLUE (-7575 2200);
FORCEPROP 2 LAST PACK_TYPE SMLF
J 0
(-7575 2225);
DISPLAY 0.617021 (-7575 2225);
FORCEPROP 2 LAST CDS_LIB pure_quanta
J 0
(-7450 2100);
DISPLAY INVISIBLE (-7450 2100);
FORCEPROP 1 LAST NEEDS_NO_SIZE TRUE
J 2
(-7450 2100);
DISPLAY 0.468085 (-7450 2100);
PAINT GREEN (-7450 2100);
DISPLAY INVISIBLE (-7450 2100);
FORCEPROP 1 LAST PATH I128
J 2
(-7525 2155);
DISPLAY 0.723404 (-7525 2155);
PAINT GREEN (-7525 2155);
DISPLAY INVISIBLE (-7525 2155);
FORCEADD UNIVERSAL_GND..1
(-7750 1975);
FORCEPROP 3 LASTPIN (-7750 2025) SIG_NAME GND\g
J 0
(-7740 2035);
DISPLAY 0.659574 (-7740 2035);
PAINT MONO (-7740 2035);
DISPLAY INVISIBLE (-7740 2035);
FORCEPROP 2 LAST CDS_LIB pure_quanta_power
J 0
(-7750 1975);
DISPLAY INVISIBLE (-7750 1975);
FORCEPROP 1 LAST PATH I129
J 0
(-7675 1975);
DISPLAY 0.872340 (-7675 1975);
PAINT AQUA (-7675 1975);
DISPLAY INVISIBLE (-7675 1975);
FORCEPROP 1 LAST HDL_POWER GND
J 1
(-7725 1900);
DISPLAY 0.872340 (-7725 1900);
PAINT GREEN (-7725 1900);
DISPLAY INVISIBLE (-7725 1900);
FORCEADD UNIVERSAL_GND..1
(-11500 4450);
FORCEPROP 3 LASTPIN (-11500 4500) SIG_NAME GND\g
J 0
(-11490 4510);
DISPLAY 0.659574 (-11490 4510);
PAINT MONO (-11490 4510);
DISPLAY INVISIBLE (-11490 4510);
FORCEPROP 2 LAST CDS_LIB pure_quanta_power
J 0
(-11500 4450);
PAINT MONO (-11500 4450);
DISPLAY INVISIBLE (-11500 4450);
FORCEPROP 1 LAST PATH I14
J 0
(-11425 4450);
DISPLAY 0.872340 (-11425 4450);
PAINT AQUA (-11425 4450);
DISPLAY INVISIBLE (-11425 4450);
FORCEPROP 1 LAST HDL_POWER GND
J 1
(-11475 4375);
DISPLAY 0.872340 (-11475 4375);
PAINT GREEN (-11475 4375);
DISPLAY INVISIBLE (-11475 4375);
FORCEADD Q_RES..2
R 2
(-11500 4675);
FORCEPROP 1 LAST LOCATION PR369
J 2
(-11545 4800);
DISPLAY 0.489362 (-11545 4800);
PAINT SKYBLUE (-11545 4800);
FORCEPROP 0 LAST $SEC 1
J 2
(-11550 4850);
DISPLAY 0.680851 (-11550 4850);
PAINT MONO (-11550 4850);
DISPLAY INVISIBLE (-11550 4850);
FORCEPROP 0 LAST CDS_SEC 1
J 2
(-11550 4850);
DISPLAY 1.021277 (-11550 4850);
DISPLAY INVISIBLE (-11550 4850);
FORCEPROP 1 LASTPIN (-11500 4775) $PN 1
J 2
(-11505 4737);
DISPLAY 0.489362 (-11505 4737);
PAINT MONO (-11505 4737);
FORCEPROP 1 LASTPIN (-11500 4575) $PN 2
J 2
(-11505 4585);
DISPLAY 0.489362 (-11505 4585);
PAINT MONO (-11505 4585);
FORCEPROP 1 LAST WATTAGE 1/16W
J 2
(-11550 4650);
DISPLAY 0.489362 (-11550 4650);
PAINT SKYBLUE (-11550 4650);
FORCEPROP 1 LAST MATERIAL EMPTY
J 2
(-11550 4600);
DISPLAY 0.489362 (-11550 4600);
PAINT RED (-11550 4600);
FORCEPROP 1 LAST TOLERANCE 1%
J 2
(-11555 4700);
DISPLAY 0.489362 (-11555 4700);
PAINT SKYBLUE (-11555 4700);
FORCEPROP 1 LAST VALUE 8.87K
J 2
(-11555 4750);
DISPLAY 0.489362 (-11555 4750);
PAINT SKYBLUE (-11555 4750);
FORCEPROP 1 LAST PART_NUMBER CS28872FB01
J 2
(-11550 4550);
DISPLAY 0.489362 (-11550 4550);
PAINT SKYBLUE (-11550 4550);
FORCEPROP 1 LAST PACK_TYPE 0402LF
J 2
(-11550 4500);
DISPLAY 0.489362 (-11550 4500);
PAINT SKYBLUE (-11550 4500);
FORCEPROP 2 LAST CDS_LIB pure_quanta
J 2
(-11500 4675);
DISPLAY INVISIBLE (-11500 4675);
FORCEPROP 1 LAST PATH I15
J 2
(-11550 4850);
DISPLAY 0.978723 (-11550 4850);
PAINT WHITE (-11550 4850);
DISPLAY INVISIBLE (-11550 4850);
FORCEADD Q_RES..2
R 2
(-11525 1825);
FORCEPROP 1 LAST LOCATION PR368
J 2
(-11570 1950);
DISPLAY 0.489362 (-11570 1950);
PAINT SKYBLUE (-11570 1950);
FORCEPROP 0 LAST $SEC 1
J 2
(-11575 2000);
DISPLAY 0.680851 (-11575 2000);
PAINT MONO (-11575 2000);
DISPLAY INVISIBLE (-11575 2000);
FORCEPROP 0 LAST CDS_SEC 1
J 2
(-11575 2000);
DISPLAY 1.021277 (-11575 2000);
DISPLAY INVISIBLE (-11575 2000);
FORCEPROP 1 LASTPIN (-11525 1925) $PN 1
J 2
(-11530 1887);
DISPLAY 0.489362 (-11530 1887);
PAINT MONO (-11530 1887);
FORCEPROP 1 LASTPIN (-11525 1725) $PN 2
J 2
(-11530 1735);
DISPLAY 0.489362 (-11530 1735);
PAINT MONO (-11530 1735);
FORCEPROP 1 LAST WATTAGE 1/16W
J 2
(-11575 1800);
DISPLAY 0.489362 (-11575 1800);
PAINT SKYBLUE (-11575 1800);
FORCEPROP 1 LAST MATERIAL EMPTY
J 2
(-11575 1750);
DISPLAY 0.489362 (-11575 1750);
PAINT RED (-11575 1750);
FORCEPROP 1 LAST TOLERANCE 1%
J 2
(-11580 1850);
DISPLAY 0.489362 (-11580 1850);
PAINT SKYBLUE (-11580 1850);
FORCEPROP 1 LAST VALUE 8.87K
J 2
(-11580 1900);
DISPLAY 0.489362 (-11580 1900);
PAINT SKYBLUE (-11580 1900);
FORCEPROP 1 LAST PART_NUMBER CS28872FB01
J 2
(-11575 1700);
DISPLAY 0.489362 (-11575 1700);
PAINT SKYBLUE (-11575 1700);
FORCEPROP 1 LAST PACK_TYPE 0402LF
J 2
(-11575 1650);
DISPLAY 0.489362 (-11575 1650);
PAINT SKYBLUE (-11575 1650);
FORCEPROP 2 LAST CDS_LIB pure_quanta
J 2
(-11525 1825);
DISPLAY INVISIBLE (-11525 1825);
FORCEPROP 1 LAST PATH I2
J 2
(-11575 2000);
DISPLAY 0.978723 (-11575 2000);
PAINT WHITE (-11575 2000);
DISPLAY INVISIBLE (-11575 2000);
FORCEADD OFFPAGE..1
(-11025 4525);
FORCEPROP 2 LAST $XR0 193 
J 0
(-11307 4525);
DISPLAY 0.638298 (-11307 4525);
PAINT MONO (-11307 4525);
FORCEPROP 2 LAST PATH I21
J 0
(-11275 4575);
DISPLAY 1.021277 (-11275 4575);
DISPLAY INVISIBLE (-11275 4575);
FORCEPROP 1 LAST COMMENT_BODY TRUE
J 0
(-10900 4425);
DISPLAY 0.872340 (-10900 4425);
PAINT GREEN (-10900 4425);
DISPLAY INVISIBLE (-10900 4425);
FORCEPROP 1 LAST OFFPAGE TRUE
J 0
(-10700 4400);
DISPLAY 0.872340 (-10700 4400);
PAINT GREEN (-10700 4400);
DISPLAY INVISIBLE (-10700 4400);
FORCEPROP 2 LAST CDS_LIB standard
J 0
(-11025 4525);
DISPLAY INVISIBLE (-11025 4525);
FORCEADD OFFPAGE..5
(-11025 4625);
FORCEPROP 2 LAST $XR2 193 
J 0
(-11280 4661);
DISPLAY 0.638298 (-11280 4661);
PAINT MONO (-11280 4661);
FORCEPROP 2 LAST $XR1 199 
J 0
(-11280 4589);
DISPLAY 0.638298 (-11280 4589);
PAINT MONO (-11280 4589);
FORCEPROP 2 LAST $XR0 198 
J 0
(-11280 4625);
DISPLAY 0.638298 (-11280 4625);
PAINT MONO (-11280 4625);
FORCEPROP 2 LAST PATH I22
J 0
(-11300 4800);
DISPLAY 1.021277 (-11300 4800);
DISPLAY INVISIBLE (-11300 4800);
FORCEPROP 1 LAST COMMENT_BODY TRUE
J 0
(-10925 4550);
DISPLAY 0.872340 (-10925 4550);
PAINT GREEN (-10925 4550);
DISPLAY INVISIBLE (-10925 4550);
FORCEPROP 1 LAST OFFPAGE TRUE
J 0
(-10700 4500);
DISPLAY 0.872340 (-10700 4500);
PAINT GREEN (-10700 4500);
DISPLAY INVISIBLE (-10700 4500);
FORCEPROP 2 LAST CDS_LIB standard
J 0
(-11025 4625);
DISPLAY INVISIBLE (-11025 4625);
FORCEADD ISL99390FRZTR5935..1
(-9500 2325);
FORCEPROP 1 LAST LOCATION PU53
J 0
(-9800 3200);
DISPLAY 0.489362 (-9800 3200);
PAINT SKYBLUE (-9800 3200);
FORCEPROP 2 LAST $SEC 1
J 0
(-9800 3250);
DISPLAY 0.680851 (-9800 3250);
PAINT MONO (-9800 3250);
DISPLAY INVISIBLE (-9800 3250);
FORCEPROP 2 LAST CDS_SEC 1
J 0
(-9750 3325);
DISPLAY 1.021277 (-9750 3325);
DISPLAY INVISIBLE (-9750 3325);
FORCEPROP 2 LASTPIN (-9100 1875) $PN 2
J 0
(-9090 1885);
DISPLAY 0.489362 (-9090 1885);
PAINT MONO (-9090 1885);
FORCEPROP 2 LASTPIN (-9100 2675) $PN 33
J 0
(-9090 2685);
DISPLAY 0.489362 (-9090 2685);
PAINT MONO (-9090 2685);
FORCEPROP 2 LASTPIN (-9950 2075) $PN 31
J 2
(-9960 2085);
DISPLAY 0.489362 (-9960 2085);
PAINT MONO (-9960 2085);
FORCEPROP 2 LASTPIN (-9950 2475) $PN 35
J 2
(-9960 2485);
DISPLAY 0.489362 (-9960 2485);
PAINT MONO (-9960 2485);
FORCEPROP 2 LASTPIN (-9100 2025) $PN 6
J 0
(-9090 2035);
DISPLAY 0.489362 (-9090 2035);
PAINT MONO (-9090 2035);
FORCEPROP 2 LASTPIN (-9100 1975) $PN 41
J 0
(-9090 1985);
DISPLAY 0.489362 (-9090 1985);
PAINT MONO (-9090 1985);
FORCEPROP 2 LASTPIN (-9950 2325) $PN 38
J 2
(-9960 2335);
DISPLAY 0.489362 (-9960 2335);
PAINT MONO (-9960 2335);
FORCEPROP 2 LASTPIN (-9950 2025) $PN 37
J 2
(-9960 2035);
DISPLAY 0.489362 (-9960 2035);
PAINT MONO (-9960 2035);
FORCEPROP 2 LASTPIN (-9100 1825) $PN 5
J 0
(-9090 1835);
DISPLAY 0.489362 (-9090 1835);
PAINT MONO (-9090 1835);
FORCEPROP 2 LASTPIN (-9100 1775) $PN 7_9-20_24
J 0
(-9090 1785);
DISPLAY 0.489362 (-9090 1785);
PAINT MONO (-9090 1785);
FORCEPROP 2 LASTPIN (-9100 1725) $PN 40
J 0
(-9090 1735);
DISPLAY 0.489362 (-9090 1735);
PAINT MONO (-9090 1735);
FORCEPROP 2 LASTPIN (-9100 2425) $PN 32
J 0
(-9090 2435);
DISPLAY 0.489362 (-9090 2435);
PAINT MONO (-9090 2435);
FORCEPROP 2 LASTPIN (-9950 2975) $PN 4
J 2
(-9960 2985);
DISPLAY 0.489362 (-9960 2985);
PAINT MONO (-9960 2985);
FORCEPROP 2 LASTPIN (-9950 1725) $PN 34
J 2
(-9960 1735);
DISPLAY 0.489362 (-9960 1735);
PAINT MONO (-9960 1735);
FORCEPROP 2 LASTPIN (-9950 2225) $PN 39
J 2
(-9960 2235);
DISPLAY 0.489362 (-9960 2235);
PAINT MONO (-9960 2235);
FORCEPROP 2 LASTPIN (-9100 2325) $PN 10_19
J 0
(-9090 2335);
DISPLAY 0.489362 (-9090 2335);
PAINT MONO (-9090 2335);
FORCEPROP 2 LASTPIN (-9950 1825) $PN 36
J 2
(-9960 1835);
DISPLAY 0.489362 (-9960 1835);
PAINT MONO (-9960 1835);
FORCEPROP 2 LASTPIN (-9950 2675) $PN 3
J 2
(-9960 2685);
DISPLAY 0.489362 (-9960 2685);
PAINT MONO (-9960 2685);
FORCEPROP 2 LASTPIN (-9100 2975) $PN 25_29
J 0
(-9090 2985);
DISPLAY 0.489362 (-9090 2985);
PAINT MONO (-9090 2985);
FORCEPROP 2 LASTPIN (-9100 2925) $PN 30
J 0
(-9090 2935);
DISPLAY 0.489362 (-9090 2935);
PAINT MONO (-9090 2935);
FORCEPROP 2 LASTPIN (-9100 2075) $PN 1
J 0
(-9090 2085);
DISPLAY 0.489362 (-9090 2085);
PAINT MONO (-9090 2085);
FORCEPROP 2 LAST PART_TYPE SMLF
J 0
(-9800 3325);
DISPLAY 0.638298 (-9800 3325);
FORCEPROP 1 LAST MATERIAL IC
J 0
(-9800 3050);
DISPLAY 0.489362 (-9800 3050);
PAINT SKYBLUE (-9800 3050);
FORCEPROP 2 LAST VALUE ISL99390FRZ-TR5935
J 0
(-9800 3275);
DISPLAY 0.489362 (-9800 3275);
PAINT SKYBLUE (-9800 3275);
FORCEPROP 1 LAST PART_NUMBER AL099390004
J 0
(-9800 3125);
DISPLAY 0.489362 (-9800 3125);
PAINT SKYBLUE (-9800 3125);
FORCEPROP 2 LAST CDS_LIB pure_quanta
J 0
(-9500 2325);
DISPLAY INVISIBLE (-9500 2325);
FORCEPROP 1 LAST CDS_LMAN_SYM_OUTLINE -300,700,250,-650
J 0
(-9500 2325);
DISPLAY 0.468085 (-9500 2325);
PAINT GREEN (-9500 2325);
DISPLAY INVISIBLE (-9500 2325);
FORCEPROP 1 LAST NEEDS_NO_SIZE TRUE
J 0
(-9500 2325);
DISPLAY 0.723404 (-9500 2325);
PAINT GREEN (-9500 2325);
DISPLAY INVISIBLE (-9500 2325);
FORCEPROP 1 LAST PATH I23
J 0
(-9500 2325);
DISPLAY 0.723404 (-9500 2325);
PAINT GREEN (-9500 2325);
DISPLAY INVISIBLE (-9500 2325);
FORCEADD UNIVERSAL_GND..1
(-8850 1600);
FORCEPROP 3 LASTPIN (-8850 1650) SIG_NAME GND\g
J 0
(-8840 1660);
DISPLAY 0.659574 (-8840 1660);
PAINT MONO (-8840 1660);
DISPLAY INVISIBLE (-8840 1660);
FORCEPROP 2 LAST CDS_LIB pure_quanta_power
J 0
(-8850 1600);
PAINT MONO (-8850 1600);
DISPLAY INVISIBLE (-8850 1600);
FORCEPROP 1 LAST PATH I24
J 0
(-8775 1600);
DISPLAY 0.872340 (-8775 1600);
PAINT AQUA (-8775 1600);
DISPLAY INVISIBLE (-8775 1600);
FORCEPROP 1 LAST HDL_POWER GND
J 1
(-8825 1525);
DISPLAY 0.872340 (-8825 1525);
PAINT GREEN (-8825 1525);
DISPLAY INVISIBLE (-8825 1525);
FORCEADD ISL99390FRZTR5935..1
(-9500 5125);
FORCEPROP 1 LAST LOCATION PU52
J 0
(-9800 6000);
DISPLAY 0.489362 (-9800 6000);
PAINT SKYBLUE (-9800 6000);
FORCEPROP 2 LAST $SEC 1
J 0
(-9800 6050);
DISPLAY 0.680851 (-9800 6050);
PAINT MONO (-9800 6050);
DISPLAY INVISIBLE (-9800 6050);
FORCEPROP 2 LAST CDS_SEC 1
J 0
(-9750 6125);
DISPLAY 1.021277 (-9750 6125);
DISPLAY INVISIBLE (-9750 6125);
FORCEPROP 2 LASTPIN (-9100 4675) $PN 2
J 0
(-9090 4685);
DISPLAY 0.489362 (-9090 4685);
PAINT MONO (-9090 4685);
FORCEPROP 2 LASTPIN (-9100 5475) $PN 33
J 0
(-9090 5485);
DISPLAY 0.489362 (-9090 5485);
PAINT MONO (-9090 5485);
FORCEPROP 2 LASTPIN (-9950 4875) $PN 31
J 2
(-9960 4885);
DISPLAY 0.489362 (-9960 4885);
PAINT MONO (-9960 4885);
FORCEPROP 2 LASTPIN (-9950 5275) $PN 35
J 2
(-9960 5285);
DISPLAY 0.489362 (-9960 5285);
PAINT MONO (-9960 5285);
FORCEPROP 2 LASTPIN (-9100 4825) $PN 6
J 0
(-9090 4835);
DISPLAY 0.489362 (-9090 4835);
PAINT MONO (-9090 4835);
FORCEPROP 2 LASTPIN (-9100 4775) $PN 41
J 0
(-9090 4785);
DISPLAY 0.489362 (-9090 4785);
PAINT MONO (-9090 4785);
FORCEPROP 2 LASTPIN (-9950 5125) $PN 38
J 2
(-9960 5135);
DISPLAY 0.489362 (-9960 5135);
PAINT MONO (-9960 5135);
FORCEPROP 2 LASTPIN (-9950 4825) $PN 37
J 2
(-9960 4835);
DISPLAY 0.489362 (-9960 4835);
PAINT MONO (-9960 4835);
FORCEPROP 2 LASTPIN (-9100 4625) $PN 5
J 0
(-9090 4635);
DISPLAY 0.489362 (-9090 4635);
PAINT MONO (-9090 4635);
FORCEPROP 2 LASTPIN (-9100 4575) $PN 7_9-20_24
J 0
(-9090 4585);
DISPLAY 0.489362 (-9090 4585);
PAINT MONO (-9090 4585);
FORCEPROP 2 LASTPIN (-9100 4525) $PN 40
J 0
(-9090 4535);
DISPLAY 0.489362 (-9090 4535);
PAINT MONO (-9090 4535);
FORCEPROP 2 LASTPIN (-9100 5225) $PN 32
J 0
(-9090 5235);
DISPLAY 0.489362 (-9090 5235);
PAINT MONO (-9090 5235);
FORCEPROP 2 LASTPIN (-9950 5775) $PN 4
J 2
(-9960 5785);
DISPLAY 0.489362 (-9960 5785);
PAINT MONO (-9960 5785);
FORCEPROP 2 LASTPIN (-9950 4525) $PN 34
J 2
(-9960 4535);
DISPLAY 0.489362 (-9960 4535);
PAINT MONO (-9960 4535);
FORCEPROP 2 LASTPIN (-9950 5025) $PN 39
J 2
(-9960 5035);
DISPLAY 0.489362 (-9960 5035);
PAINT MONO (-9960 5035);
FORCEPROP 2 LASTPIN (-9100 5125) $PN 10_19
J 0
(-9090 5135);
DISPLAY 0.489362 (-9090 5135);
PAINT MONO (-9090 5135);
FORCEPROP 2 LASTPIN (-9950 4625) $PN 36
J 2
(-9960 4635);
DISPLAY 0.489362 (-9960 4635);
PAINT MONO (-9960 4635);
FORCEPROP 2 LASTPIN (-9950 5475) $PN 3
J 2
(-9960 5485);
DISPLAY 0.489362 (-9960 5485);
PAINT MONO (-9960 5485);
FORCEPROP 2 LASTPIN (-9100 5775) $PN 25_29
J 0
(-9090 5785);
DISPLAY 0.489362 (-9090 5785);
PAINT MONO (-9090 5785);
FORCEPROP 2 LASTPIN (-9100 5725) $PN 30
J 0
(-9090 5735);
DISPLAY 0.489362 (-9090 5735);
PAINT MONO (-9090 5735);
FORCEPROP 2 LASTPIN (-9100 4875) $PN 1
J 0
(-9090 4885);
DISPLAY 0.489362 (-9090 4885);
PAINT MONO (-9090 4885);
FORCEPROP 2 LAST PART_TYPE SMLF
J 0
(-9800 6150);
DISPLAY 0.638298 (-9800 6150);
FORCEPROP 1 LAST MATERIAL IC
J 0
(-9800 5850);
DISPLAY 0.489362 (-9800 5850);
PAINT SKYBLUE (-9800 5850);
FORCEPROP 2 LAST VALUE ISL99390FRZ-TR5935
J 0
(-9800 6100);
DISPLAY 0.489362 (-9800 6100);
PAINT SKYBLUE (-9800 6100);
FORCEPROP 1 LAST PART_NUMBER AL099390004
J 0
(-9800 5925);
DISPLAY 0.489362 (-9800 5925);
PAINT SKYBLUE (-9800 5925);
FORCEPROP 2 LAST CDS_LIB pure_quanta
J 0
(-9500 5125);
DISPLAY INVISIBLE (-9500 5125);
FORCEPROP 1 LAST CDS_LMAN_SYM_OUTLINE -300,700,250,-650
J 0
(-9500 5125);
DISPLAY 0.468085 (-9500 5125);
PAINT GREEN (-9500 5125);
DISPLAY INVISIBLE (-9500 5125);
FORCEPROP 1 LAST NEEDS_NO_SIZE TRUE
J 0
(-9500 5125);
DISPLAY 0.723404 (-9500 5125);
PAINT GREEN (-9500 5125);
DISPLAY INVISIBLE (-9500 5125);
FORCEPROP 1 LAST PATH I26
J 0
(-9500 5125);
DISPLAY 0.723404 (-9500 5125);
PAINT GREEN (-9500 5125);
DISPLAY INVISIBLE (-9500 5125);
FORCEADD Q_CAP..1
(-8150 3275);
FORCEPROP 1 LAST LOCATION PC625_4
J 0
(-8100 3425);
DISPLAY 0.489362 (-8100 3425);
PAINT SKYBLUE (-8100 3425);
FORCEPROP 0 LAST $SEC 1
J 0
(-8100 3475);
DISPLAY 0.680851 (-8100 3475);
PAINT MONO (-8100 3475);
DISPLAY INVISIBLE (-8100 3475);
FORCEPROP 0 LAST CDS_SEC 1
J 0
(-8100 3475);
DISPLAY 1.021277 (-8100 3475);
DISPLAY INVISIBLE (-8100 3475);
FORCEPROP 1 LASTPIN (-8150 3375) $PN 1
J 0
(-8140 3355);
DISPLAY 0.489362 (-8140 3355);
PAINT MONO (-8140 3355);
FORCEPROP 1 LASTPIN (-8150 3175) $PN 2
J 0
(-8140 3155);
DISPLAY 0.489362 (-8140 3155);
PAINT MONO (-8140 3155);
FORCEPROP 1 LAST MATERIAL X6S
J 0
(-8100 3225);
DISPLAY 0.489362 (-8100 3225);
PAINT SKYBLUE (-8100 3225);
FORCEPROP 1 LAST TOLERANCE 10%
J 0
(-8100 3275);
DISPLAY 0.489362 (-8100 3275);
PAINT SKYBLUE (-8100 3275);
FORCEPROP 1 LAST VALUE 1UF
J 0
(-8100 3375);
DISPLAY 0.489362 (-8100 3375);
PAINT SKYBLUE (-8100 3375);
FORCEPROP 1 LAST PART_NUMBER CH5104KEB02
J 0
(-8100 3125);
DISPLAY 0.489362 (-8100 3125);
PAINT SKYBLUE (-8100 3125);
FORCEPROP 1 LAST VOLTAGE 25V
J 0
(-8100 3325);
DISPLAY 0.489362 (-8100 3325);
PAINT SKYBLUE (-8100 3325);
FORCEPROP 1 LAST PACK_TYPE C0402
J 0
(-8100 3175);
DISPLAY 0.489362 (-8100 3175);
PAINT SKYBLUE (-8100 3175);
FORCEPROP 2 LAST CDS_LIB pure_quanta
J 0
(-8150 3275);
DISPLAY INVISIBLE (-8150 3275);
FORCEPROP 1 LAST PATH I28
J 0
(-8100 3425);
DISPLAY 0.978723 (-8100 3425);
PAINT WHITE (-8100 3425);
DISPLAY INVISIBLE (-8100 3425);
FORCEADD UNIVERSAL_GND..1
(-8850 4400);
FORCEPROP 3 LASTPIN (-8850 4450) SIG_NAME GND\g
J 0
(-8840 4460);
DISPLAY 0.659574 (-8840 4460);
PAINT MONO (-8840 4460);
DISPLAY INVISIBLE (-8840 4460);
FORCEPROP 2 LAST CDS_LIB pure_quanta_power
J 0
(-8850 4400);
PAINT MONO (-8850 4400);
DISPLAY INVISIBLE (-8850 4400);
FORCEPROP 1 LAST PATH I29
J 0
(-8775 4400);
DISPLAY 0.872340 (-8775 4400);
PAINT AQUA (-8775 4400);
DISPLAY INVISIBLE (-8775 4400);
FORCEPROP 1 LAST HDL_POWER GND
J 1
(-8825 4325);
DISPLAY 0.872340 (-8825 4325);
PAINT GREEN (-8825 4325);
DISPLAY INVISIBLE (-8825 4325);
FORCEADD OFFPAGE..1
(-11025 5025);
FORCEPROP 2 LAST $XR5 199 
J 0
(-11907 5025);
DISPLAY 0.638298 (-11907 5025);
PAINT MONO (-11907 5025);
FORCEPROP 2 LAST $XR4 198 
J 0
(-11787 5025);
DISPLAY 0.638298 (-11787 5025);
PAINT MONO (-11787 5025);
FORCEPROP 2 LAST $XR3 196 
J 0
(-11667 5025);
DISPLAY 0.638298 (-11667 5025);
PAINT MONO (-11667 5025);
FORCEPROP 2 LAST $XR2 195 
J 0
(-11547 5025);
DISPLAY 0.638298 (-11547 5025);
PAINT MONO (-11547 5025);
FORCEPROP 2 LAST $XR1 194 
J 0
(-11427 5025);
DISPLAY 0.638298 (-11427 5025);
PAINT MONO (-11427 5025);
FORCEPROP 2 LAST $XR0 193 
J 0
(-11307 5025);
DISPLAY 0.638298 (-11307 5025);
PAINT MONO (-11307 5025);
FORCEPROP 2 LAST PATH I33
J 0
(-11275 5075);
DISPLAY 1.021277 (-11275 5075);
DISPLAY INVISIBLE (-11275 5075);
FORCEPROP 1 LAST COMMENT_BODY TRUE
J 0
(-10900 4925);
DISPLAY 0.872340 (-10900 4925);
PAINT GREEN (-10900 4925);
DISPLAY INVISIBLE (-10900 4925);
FORCEPROP 1 LAST OFFPAGE TRUE
J 0
(-10700 4900);
DISPLAY 0.872340 (-10700 4900);
PAINT GREEN (-10700 4900);
DISPLAY INVISIBLE (-10700 4900);
FORCEPROP 2 LAST CDS_LIB standard
J 0
(-11025 5025);
DISPLAY INVISIBLE (-11025 5025);
FORCEADD OFFPAGE..5
(-11025 5125);
FORCEPROP 2 LAST $XR0 193 
J 0
(-11280 5125);
DISPLAY 0.638298 (-11280 5125);
PAINT MONO (-11280 5125);
FORCEPROP 2 LAST PATH I34
J 0
(-11300 5175);
DISPLAY 1.021277 (-11300 5175);
DISPLAY INVISIBLE (-11300 5175);
FORCEPROP 1 LAST COMMENT_BODY TRUE
J 0
(-10925 5050);
DISPLAY 0.872340 (-10925 5050);
PAINT GREEN (-10925 5050);
DISPLAY INVISIBLE (-10925 5050);
FORCEPROP 1 LAST OFFPAGE TRUE
J 0
(-10700 5000);
DISPLAY 0.872340 (-10700 5000);
PAINT GREEN (-10700 5000);
DISPLAY INVISIBLE (-10700 5000);
FORCEPROP 2 LAST CDS_LIB standard
J 0
(-11025 5125);
DISPLAY INVISIBLE (-11025 5125);
FORCEADD OFFPAGE..1
(-11050 1725);
FORCEPROP 2 LAST $XR0 193 
J 0
(-11302 1725);
DISPLAY 0.638298 (-11302 1725);
PAINT MONO (-11302 1725);
FORCEPROP 2 LAST PATH I4
J 0
(-11300 1775);
DISPLAY 1.021277 (-11300 1775);
DISPLAY INVISIBLE (-11300 1775);
FORCEPROP 1 LAST COMMENT_BODY TRUE
J 0
(-10925 1625);
DISPLAY 0.872340 (-10925 1625);
PAINT GREEN (-10925 1625);
DISPLAY INVISIBLE (-10925 1625);
FORCEPROP 1 LAST OFFPAGE TRUE
J 0
(-10725 1600);
DISPLAY 0.872340 (-10725 1600);
PAINT GREEN (-10725 1600);
DISPLAY INVISIBLE (-10725 1600);
FORCEPROP 2 LAST CDS_LIB standard
J 0
(-11050 1725);
DISPLAY INVISIBLE (-11050 1725);
FORCEADD Q_CAP..1
(-8225 6075);
FORCEPROP 1 LAST LOCATION PC624_3
J 0
(-8175 6225);
DISPLAY 0.489362 (-8175 6225);
PAINT SKYBLUE (-8175 6225);
FORCEPROP 0 LAST $SEC 1
J 0
(-8175 6275);
DISPLAY 0.680851 (-8175 6275);
PAINT MONO (-8175 6275);
DISPLAY INVISIBLE (-8175 6275);
FORCEPROP 0 LAST CDS_SEC 1
J 0
(-8175 6275);
DISPLAY 1.021277 (-8175 6275);
DISPLAY INVISIBLE (-8175 6275);
FORCEPROP 1 LASTPIN (-8225 6175) $PN 1
J 0
(-8215 6155);
DISPLAY 0.489362 (-8215 6155);
PAINT MONO (-8215 6155);
FORCEPROP 1 LASTPIN (-8225 5975) $PN 2
J 0
(-8215 5955);
DISPLAY 0.489362 (-8215 5955);
PAINT MONO (-8215 5955);
FORCEPROP 1 LAST MATERIAL X6S
J 0
(-8175 6025);
DISPLAY 0.489362 (-8175 6025);
PAINT SKYBLUE (-8175 6025);
FORCEPROP 1 LAST TOLERANCE 10%
J 0
(-8175 6075);
DISPLAY 0.489362 (-8175 6075);
PAINT SKYBLUE (-8175 6075);
FORCEPROP 1 LAST VALUE 1UF
J 0
(-8175 6175);
DISPLAY 0.489362 (-8175 6175);
PAINT SKYBLUE (-8175 6175);
FORCEPROP 1 LAST PART_NUMBER CH5104KEB02
J 0
(-8175 5925);
DISPLAY 0.489362 (-8175 5925);
PAINT SKYBLUE (-8175 5925);
FORCEPROP 1 LAST VOLTAGE 25V
J 0
(-8175 6125);
DISPLAY 0.489362 (-8175 6125);
PAINT SKYBLUE (-8175 6125);
FORCEPROP 1 LAST PACK_TYPE C0402
J 0
(-8175 5975);
DISPLAY 0.489362 (-8175 5975);
PAINT SKYBLUE (-8175 5975);
FORCEPROP 2 LAST CDS_LIB pure_quanta
J 0
(-8225 6075);
DISPLAY INVISIBLE (-8225 6075);
FORCEPROP 1 LAST PATH I44
J 0
(-8175 6225);
DISPLAY 0.978723 (-8175 6225);
PAINT WHITE (-8175 6225);
DISPLAY INVISIBLE (-8175 6225);
FORCEADD Q_INDUCTOR4P_14..1
(-6425 2200);
FORCEPROP 1 LAST LOCATION PL67
J 0
(-6700 2375);
DISPLAY 0.489362 (-6700 2375);
PAINT SKYBLUE (-6700 2375);
FORCEPROP 0 LAST $SEC 1
J 0
(-6375 2400);
DISPLAY 0.680851 (-6375 2400);
PAINT MONO (-6375 2400);
DISPLAY INVISIBLE (-6375 2400);
FORCEPROP 0 LAST CDS_SEC 1
J 0
(-6375 2400);
DISPLAY 1.021277 (-6375 2400);
DISPLAY INVISIBLE (-6375 2400);
FORCEPROP 0 LASTPIN (-6825 2325) $PN 1
J 2
(-6835 2335);
DISPLAY 0.489362 (-6835 2335);
PAINT MONO (-6835 2335);
FORCEPROP 0 LASTPIN (-6825 2075) $PN 2
J 2
(-6835 2085);
DISPLAY 0.489362 (-6835 2085);
PAINT MONO (-6835 2085);
FORCEPROP 0 LASTPIN (-6025 2075) $PN 3
J 0
(-6015 2085);
DISPLAY 0.489362 (-6015 2085);
PAINT MONO (-6015 2085);
FORCEPROP 0 LASTPIN (-6025 2325) $PN 4
J 0
(-6015 2335);
DISPLAY 0.489362 (-6015 2335);
PAINT MONO (-6015 2335);
FORCEPROP 2 LAST PART_TYPE SMLF
J 0
(-6500 1950);
DISPLAY 1.021277 (-6500 1950);
FORCEPROP 1 LAST MATERIAL IND
J 0
(-6625 2375);
DISPLAY 0.489362 (-6625 2375);
PAINT SKYBLUE (-6625 2375);
FORCEPROP 1 LAST PART_NUMBER CV+15^0TZ04
J 0
(-6375 2375);
DISPLAY 0.489362 (-6375 2375);
PAINT SKYBLUE (-6375 2375);
FORCEPROP 2 LAST VALUE 150NH
J 0
(-6525 2375);
DISPLAY 0.489362 (-6525 2375);
PAINT SKYBLUE (-6525 2375);
FORCEPROP 2 LAST CDS_LIB pure_quanta
J 0
(-6425 2200);
DISPLAY INVISIBLE (-6425 2200);
FORCEPROP 1 LAST NEEDS_NO_SIZE TRUE
J 0
(-6425 2200);
DISPLAY 0.468085 (-6425 2200);
PAINT GREEN (-6425 2200);
DISPLAY INVISIBLE (-6425 2200);
FORCEPROP 1 LAST PATH I46
J 0
(-6225 2355);
DISPLAY 0.723404 (-6225 2355);
PAINT GREEN (-6225 2355);
DISPLAY INVISIBLE (-6225 2355);
FORCEADD UNIVERSAL_GND..1
(-6875 2900);
FORCEPROP 3 LASTPIN (-6875 2950) SIG_NAME GND\g
J 0
(-6865 2960);
DISPLAY 0.659574 (-6865 2960);
PAINT MONO (-6865 2960);
DISPLAY INVISIBLE (-6865 2960);
FORCEPROP 2 LAST CDS_LIB pure_quanta_power
J 0
(-6875 2900);
PAINT MONO (-6875 2900);
DISPLAY INVISIBLE (-6875 2900);
FORCEPROP 1 LAST PATH I49
J 0
(-6800 2900);
DISPLAY 0.872340 (-6800 2900);
PAINT AQUA (-6800 2900);
DISPLAY INVISIBLE (-6800 2900);
FORCEPROP 1 LAST HDL_POWER GND
J 1
(-6850 2825);
DISPLAY 0.872340 (-6850 2825);
PAINT GREEN (-6850 2825);
DISPLAY INVISIBLE (-6850 2825);
FORCEADD OFFPAGE..5
(-11050 1825);
FORCEPROP 2 LAST $XR2 193 
J 0
(-11335 1861);
DISPLAY 0.638298 (-11335 1861);
PAINT MONO (-11335 1861);
FORCEPROP 2 LAST $XR1 199 
J 0
(-11335 1789);
DISPLAY 0.638298 (-11335 1789);
PAINT MONO (-11335 1789);
FORCEPROP 2 LAST $XR0 198 
J 0
(-11335 1825);
DISPLAY 0.638298 (-11335 1825);
PAINT MONO (-11335 1825);
FORCEPROP 2 LAST PATH I5
J 0
(-11325 2000);
DISPLAY 1.021277 (-11325 2000);
DISPLAY INVISIBLE (-11325 2000);
FORCEPROP 1 LAST COMMENT_BODY TRUE
J 0
(-10950 1750);
DISPLAY 0.872340 (-10950 1750);
PAINT GREEN (-10950 1750);
DISPLAY INVISIBLE (-10950 1750);
FORCEPROP 1 LAST OFFPAGE TRUE
J 0
(-10725 1700);
DISPLAY 0.872340 (-10725 1700);
PAINT GREEN (-10725 1700);
DISPLAY INVISIBLE (-10725 1700);
FORCEPROP 2 LAST CDS_LIB standard
J 0
(-11050 1825);
DISPLAY INVISIBLE (-11050 1825);
FORCEADD Q_CAP..1
(-7750 3275);
FORCEPROP 1 LAST LOCATION PC627_4
J 0
(-7700 3425);
DISPLAY 0.489362 (-7700 3425);
PAINT SKYBLUE (-7700 3425);
FORCEPROP 0 LAST $SEC 1
J 0
(-7700 3475);
DISPLAY 0.680851 (-7700 3475);
PAINT MONO (-7700 3475);
DISPLAY INVISIBLE (-7700 3475);
FORCEPROP 0 LAST CDS_SEC 1
J 0
(-7700 3475);
DISPLAY 1.021277 (-7700 3475);
DISPLAY INVISIBLE (-7700 3475);
FORCEPROP 1 LASTPIN (-7750 3375) $PN 1
J 0
(-7740 3355);
DISPLAY 0.489362 (-7740 3355);
PAINT MONO (-7740 3355);
FORCEPROP 1 LASTPIN (-7750 3175) $PN 2
J 0
(-7740 3155);
DISPLAY 0.489362 (-7740 3155);
PAINT MONO (-7740 3155);
FORCEPROP 1 LAST MATERIAL X6S
J 0
(-7700 3225);
DISPLAY 0.489362 (-7700 3225);
PAINT SKYBLUE (-7700 3225);
FORCEPROP 1 LAST TOLERANCE 10%
J 0
(-7700 3275);
DISPLAY 0.489362 (-7700 3275);
PAINT SKYBLUE (-7700 3275);
FORCEPROP 1 LAST VALUE 10UF
J 0
(-7700 3375);
DISPLAY 0.489362 (-7700 3375);
PAINT SKYBLUE (-7700 3375);
FORCEPROP 1 LAST VOLTAGE 25V
J 0
(-7700 3325);
DISPLAY 0.489362 (-7700 3325);
PAINT SKYBLUE (-7700 3325);
FORCEPROP 1 LAST PACK_TYPE C0805
J 0
(-7700 3175);
DISPLAY 0.489362 (-7700 3175);
PAINT SKYBLUE (-7700 3175);
FORCEPROP 1 LAST PART_NUMBER CH6104KEA00
J 0
(-7700 3125);
DISPLAY 0.489362 (-7700 3125);
PAINT SKYBLUE (-7700 3125);
FORCEPROP 2 LAST CDS_LIB pure_quanta
J 0
(-7750 3275);
DISPLAY INVISIBLE (-7750 3275);
FORCEPROP 1 LAST PATH I51
J 0
(-7700 3425);
DISPLAY 0.978723 (-7700 3425);
PAINT WHITE (-7700 3425);
DISPLAY INVISIBLE (-7700 3425);
FORCEADD Q_CAP..1
(-7350 3275);
FORCEPROP 1 LAST LOCATION PC629_4
J 0
(-7300 3425);
DISPLAY 0.489362 (-7300 3425);
PAINT SKYBLUE (-7300 3425);
FORCEPROP 0 LAST $SEC 1
J 0
(-7300 3475);
DISPLAY 0.680851 (-7300 3475);
PAINT MONO (-7300 3475);
DISPLAY INVISIBLE (-7300 3475);
FORCEPROP 0 LAST CDS_SEC 1
J 0
(-7300 3475);
DISPLAY 1.021277 (-7300 3475);
DISPLAY INVISIBLE (-7300 3475);
FORCEPROP 1 LASTPIN (-7350 3375) $PN 1
J 0
(-7340 3355);
DISPLAY 0.489362 (-7340 3355);
PAINT MONO (-7340 3355);
FORCEPROP 1 LASTPIN (-7350 3175) $PN 2
J 0
(-7340 3155);
DISPLAY 0.489362 (-7340 3155);
PAINT MONO (-7340 3155);
FORCEPROP 1 LAST MATERIAL X6S
J 0
(-7300 3225);
DISPLAY 0.489362 (-7300 3225);
PAINT SKYBLUE (-7300 3225);
FORCEPROP 1 LAST TOLERANCE 10%
J 0
(-7300 3275);
DISPLAY 0.489362 (-7300 3275);
PAINT SKYBLUE (-7300 3275);
FORCEPROP 1 LAST VALUE 10UF
J 0
(-7300 3375);
DISPLAY 0.489362 (-7300 3375);
PAINT SKYBLUE (-7300 3375);
FORCEPROP 1 LAST PART_NUMBER CH6104KEA00
J 0
(-7300 3125);
DISPLAY 0.489362 (-7300 3125);
PAINT SKYBLUE (-7300 3125);
FORCEPROP 1 LAST VOLTAGE 25V
J 0
(-7300 3325);
DISPLAY 0.489362 (-7300 3325);
PAINT SKYBLUE (-7300 3325);
FORCEPROP 1 LAST PACK_TYPE C0805
J 0
(-7300 3175);
DISPLAY 0.489362 (-7300 3175);
PAINT SKYBLUE (-7300 3175);
FORCEPROP 2 LAST CDS_LIB pure_quanta
J 0
(-7350 3275);
DISPLAY INVISIBLE (-7350 3275);
FORCEPROP 1 LAST PATH I52
J 0
(-7300 3425);
DISPLAY 0.978723 (-7300 3425);
PAINT WHITE (-7300 3425);
DISPLAY INVISIBLE (-7300 3425);
FORCEADD Q_CAP..1
(-6875 3275);
FORCEPROP 1 LAST LOCATION PC633_4
J 0
(-6825 3375);
DISPLAY 0.489362 (-6825 3375);
PAINT SKYBLUE (-6825 3375);
FORCEPROP 0 LAST $SEC 1
J 0
(-6825 3425);
DISPLAY 0.680851 (-6825 3425);
PAINT MONO (-6825 3425);
DISPLAY INVISIBLE (-6825 3425);
FORCEPROP 0 LAST CDS_SEC 1
J 0
(-6825 3425);
DISPLAY 1.021277 (-6825 3425);
DISPLAY INVISIBLE (-6825 3425);
FORCEPROP 1 LASTPIN (-6875 3375) $PN 1
J 0
(-6865 3355);
DISPLAY 0.489362 (-6865 3355);
PAINT MONO (-6865 3355);
FORCEPROP 1 LASTPIN (-6875 3175) $PN 2
J 0
(-6865 3155);
DISPLAY 0.489362 (-6865 3155);
PAINT MONO (-6865 3155);
FORCEPROP 1 LAST TOLERANCE 10%
J 0
(-6825 3225);
DISPLAY 0.489362 (-6825 3225);
PAINT SKYBLUE (-6825 3225);
FORCEPROP 1 LAST VALUE 10UF
J 0
(-6825 3325);
DISPLAY 0.489362 (-6825 3325);
PAINT SKYBLUE (-6825 3325);
FORCEPROP 1 LAST VOLTAGE 25V
J 0
(-6825 3275);
DISPLAY 0.489362 (-6825 3275);
PAINT SKYBLUE (-6825 3275);
FORCEPROP 1 LAST PACK_TYPE C0805
J 0
(-6825 3075);
DISPLAY 0.489362 (-6825 3075);
PAINT SKYBLUE (-6825 3075);
FORCEPROP 1 LAST PART_NUMBER CH6104KEA00
J 0
(-6825 3125);
DISPLAY 0.489362 (-6825 3125);
PAINT SKYBLUE (-6825 3125);
FORCEPROP 1 LAST MATERIAL X6S
J 0
(-6825 3175);
DISPLAY 0.489362 (-6825 3175);
PAINT SKYBLUE (-6825 3175);
FORCEPROP 2 LAST CDS_LIB pure_quanta
J 0
(-6875 3275);
DISPLAY INVISIBLE (-6875 3275);
FORCEPROP 1 LAST PATH I55
J 0
(-6825 3425);
DISPLAY 0.978723 (-6825 3425);
PAINT WHITE (-6825 3425);
DISPLAY INVISIBLE (-6825 3425);
FORCEADD Q_RES..1
(-7100 4100);
FORCEPROP 1 LAST LOCATION PR374
J 0
(-7125 4150);
DISPLAY 0.489362 (-7125 4150);
PAINT SKYBLUE (-7125 4150);
FORCEPROP 0 LAST $SEC 1
J 0
(-7225 4275);
DISPLAY 0.680851 (-7225 4275);
PAINT MONO (-7225 4275);
DISPLAY INVISIBLE (-7225 4275);
FORCEPROP 0 LAST CDS_SEC 1
J 0
(-7225 4275);
DISPLAY 1.021277 (-7225 4275);
DISPLAY INVISIBLE (-7225 4275);
FORCEPROP 1 LASTPIN (-7200 4100) $PN 1
J 0
(-7188 4112);
DISPLAY 0.787234 (-7188 4112);
PAINT MONO (-7188 4112);
DISPLAY INVISIBLE (-7188 4112);
FORCEPROP 1 LASTPIN (-7000 4100) $PN 2
J 0
(-7038 4112);
DISPLAY 0.787234 (-7038 4112);
PAINT MONO (-7038 4112);
DISPLAY INVISIBLE (-7038 4112);
FORCEPROP 1 LAST WATTAGE 1/16W
J 2
(-6850 4150);
DISPLAY 0.489362 (-6850 4150);
PAINT SKYBLUE (-6850 4150);
FORCEPROP 1 LAST MATERIAL CHIP
J 0
(-6975 4000);
DISPLAY 0.489362 (-6975 4000);
PAINT SKYBLUE (-6975 4000);
FORCEPROP 1 LAST TOLERANCE 5%
J 0
(-7275 4000);
DISPLAY 0.489362 (-7275 4000);
PAINT SKYBLUE (-7275 4000);
FORCEPROP 1 LAST VALUE 0
J 2
(-7300 4150);
DISPLAY 0.489362 (-7300 4150);
PAINT SKYBLUE (-7300 4150);
FORCEPROP 1 LAST PART_NUMBER CS00002JB38
J 0
(-7400 4050);
DISPLAY 0.489362 (-7400 4050);
PAINT SKYBLUE (-7400 4050);
FORCEPROP 1 LAST PACK_TYPE 0402LF
J 0
(-7000 4050);
DISPLAY 0.489362 (-7000 4050);
PAINT SKYBLUE (-7000 4050);
FORCEPROP 2 LAST CDS_LIB pure_quanta
J 0
(-7100 4100);
DISPLAY INVISIBLE (-7100 4100);
FORCEPROP 1 LAST PATH I57
J 0
(-7150 4250);
DISPLAY 0.978723 (-7150 4250);
PAINT WHITE (-7150 4250);
DISPLAY INVISIBLE (-7150 4250);
FORCEADD Q_CAP..1
(-4625 2125);
FORCEPROP 1 LAST LOCATION PC634_4
J 0
(-4575 2250);
DISPLAY 0.489362 (-4575 2250);
PAINT SKYBLUE (-4575 2250);
FORCEPROP 0 LAST $SEC 1
J 0
(-4575 2300);
DISPLAY 0.680851 (-4575 2300);
PAINT MONO (-4575 2300);
DISPLAY INVISIBLE (-4575 2300);
FORCEPROP 0 LAST CDS_SEC 1
J 0
(-4575 2300);
DISPLAY 1.021277 (-4575 2300);
DISPLAY INVISIBLE (-4575 2300);
FORCEPROP 1 LASTPIN (-4625 2225) $PN 1
J 0
(-4615 2205);
DISPLAY 0.489362 (-4615 2205);
PAINT MONO (-4615 2205);
FORCEPROP 1 LASTPIN (-4625 2025) $PN 2
J 0
(-4615 2005);
DISPLAY 0.489362 (-4615 2005);
PAINT MONO (-4615 2005);
FORCEPROP 1 LAST MATERIAL X6S
J 0
(-4575 2050);
DISPLAY 0.489362 (-4575 2050);
PAINT SKYBLUE (-4575 2050);
FORCEPROP 1 LAST TOLERANCE 20%
J 0
(-4575 2100);
DISPLAY 0.489362 (-4575 2100);
PAINT SKYBLUE (-4575 2100);
FORCEPROP 1 LAST VALUE 22UF
J 0
(-4575 2200);
DISPLAY 0.489362 (-4575 2200);
PAINT SKYBLUE (-4575 2200);
FORCEPROP 1 LAST PART_NUMBER TMP_QCH622KMEA01
J 0
(-4575 1950);
DISPLAY 0.489362 (-4575 1950);
PAINT SKYBLUE (-4575 1950);
FORCEPROP 1 LAST VOLTAGE 4V
J 0
(-4575 2150);
DISPLAY 0.489362 (-4575 2150);
PAINT SKYBLUE (-4575 2150);
FORCEPROP 1 LAST PACK_TYPE 0805
J 0
(-4575 2000);
DISPLAY 0.489362 (-4575 2000);
PAINT SKYBLUE (-4575 2000);
FORCEPROP 2 LAST CDS_LIB pure_quanta
J 0
(-4625 2125);
DISPLAY INVISIBLE (-4625 2125);
FORCEPROP 1 LAST PATH I59
J 0
(-4575 2275);
DISPLAY 0.978723 (-4575 2275);
PAINT WHITE (-4575 2275);
DISPLAY INVISIBLE (-4575 2275);
FORCEADD OFFPAGE..1
(-11050 2225);
FORCEPROP 2 LAST $XR5 199 
J 0
(-11902 2225);
DISPLAY 0.638298 (-11902 2225);
PAINT MONO (-11902 2225);
FORCEPROP 2 LAST $XR4 198 
J 0
(-11782 2225);
DISPLAY 0.638298 (-11782 2225);
PAINT MONO (-11782 2225);
FORCEPROP 2 LAST $XR3 196 
J 0
(-11662 2225);
DISPLAY 0.638298 (-11662 2225);
PAINT MONO (-11662 2225);
FORCEPROP 2 LAST $XR2 195 
J 0
(-11542 2225);
DISPLAY 0.638298 (-11542 2225);
PAINT MONO (-11542 2225);
FORCEPROP 2 LAST $XR1 194 
J 0
(-11422 2225);
DISPLAY 0.638298 (-11422 2225);
PAINT MONO (-11422 2225);
FORCEPROP 2 LAST $XR0 193 
J 0
(-11302 2225);
DISPLAY 0.638298 (-11302 2225);
PAINT MONO (-11302 2225);
FORCEPROP 2 LAST PATH I6
J 0
(-11300 2275);
DISPLAY 1.021277 (-11300 2275);
DISPLAY INVISIBLE (-11300 2275);
FORCEPROP 1 LAST COMMENT_BODY TRUE
J 0
(-10925 2125);
DISPLAY 0.872340 (-10925 2125);
PAINT GREEN (-10925 2125);
DISPLAY INVISIBLE (-10925 2125);
FORCEPROP 1 LAST OFFPAGE TRUE
J 0
(-10725 2100);
DISPLAY 0.872340 (-10725 2100);
PAINT GREEN (-10725 2100);
DISPLAY INVISIBLE (-10725 2100);
FORCEPROP 2 LAST CDS_LIB standard
J 0
(-11050 2225);
DISPLAY INVISIBLE (-11050 2225);
FORCEADD OFFPAGE..3
(-5100 4875);
FORCEPROP 2 LAST $XR0 198 
J 0
(-4886 4875);
DISPLAY 0.638298 (-4886 4875);
PAINT MONO (-4886 4875);
FORCEPROP 2 LAST PATH I61
J 0
(-4900 4950);
DISPLAY 1.021277 (-4900 4950);
DISPLAY INVISIBLE (-4900 4950);
FORCEPROP 1 LAST COMMENT_BODY TRUE
J 0
(-5150 4775);
DISPLAY 0.872340 (-5150 4775);
PAINT GREEN (-5150 4775);
DISPLAY INVISIBLE (-5150 4775);
FORCEPROP 1 LAST OFFPAGE TRUE
J 0
(-4775 4750);
DISPLAY 0.872340 (-4775 4750);
PAINT GREEN (-4775 4750);
DISPLAY INVISIBLE (-4775 4750);
FORCEPROP 2 LAST CDS_LIB standard
J 0
(-5100 4875);
DISPLAY INVISIBLE (-5100 4875);
FORCEADD Q_CAP..1
(-4300 4925);
FORCEPROP 1 LAST LOCATION PC635_3
J 0
(-4250 5050);
DISPLAY 0.489362 (-4250 5050);
PAINT SKYBLUE (-4250 5050);
FORCEPROP 0 LAST $SEC 1
J 0
(-4250 5100);
DISPLAY 0.680851 (-4250 5100);
PAINT MONO (-4250 5100);
DISPLAY INVISIBLE (-4250 5100);
FORCEPROP 0 LAST CDS_SEC 1
J 0
(-4250 5100);
DISPLAY 1.021277 (-4250 5100);
DISPLAY INVISIBLE (-4250 5100);
FORCEPROP 1 LASTPIN (-4300 5025) $PN 1
J 0
(-4290 5005);
DISPLAY 0.489362 (-4290 5005);
PAINT MONO (-4290 5005);
FORCEPROP 1 LASTPIN (-4300 4825) $PN 2
J 0
(-4290 4805);
DISPLAY 0.489362 (-4290 4805);
PAINT MONO (-4290 4805);
FORCEPROP 1 LAST MATERIAL X6S
J 0
(-4250 4850);
DISPLAY 0.489362 (-4250 4850);
PAINT SKYBLUE (-4250 4850);
FORCEPROP 1 LAST TOLERANCE 20%
J 0
(-4250 4900);
DISPLAY 0.489362 (-4250 4900);
PAINT SKYBLUE (-4250 4900);
FORCEPROP 1 LAST VALUE 22UF
J 0
(-4250 5000);
DISPLAY 0.489362 (-4250 5000);
PAINT SKYBLUE (-4250 5000);
FORCEPROP 1 LAST PART_NUMBER TMP_QCH622KMEA01
J 0
(-4250 4750);
DISPLAY 0.489362 (-4250 4750);
PAINT SKYBLUE (-4250 4750);
FORCEPROP 1 LAST VOLTAGE 4V
J 0
(-4250 4950);
DISPLAY 0.489362 (-4250 4950);
PAINT SKYBLUE (-4250 4950);
FORCEPROP 1 LAST PACK_TYPE 0805
J 0
(-4250 4800);
DISPLAY 0.489362 (-4250 4800);
PAINT SKYBLUE (-4250 4800);
FORCEPROP 2 LAST CDS_LIB pure_quanta
J 0
(-4300 4925);
DISPLAY INVISIBLE (-4300 4925);
FORCEPROP 1 LAST PATH I65
J 0
(-4250 5075);
DISPLAY 0.978723 (-4250 5075);
PAINT WHITE (-4250 5075);
DISPLAY INVISIBLE (-4250 5075);
FORCEADD Q_CAP..1
(-7825 6075);
FORCEPROP 1 LAST LOCATION PC626_3
J 0
(-7775 6225);
DISPLAY 0.489362 (-7775 6225);
PAINT SKYBLUE (-7775 6225);
FORCEPROP 0 LAST $SEC 1
J 0
(-7775 6275);
DISPLAY 0.680851 (-7775 6275);
PAINT MONO (-7775 6275);
DISPLAY INVISIBLE (-7775 6275);
FORCEPROP 0 LAST CDS_SEC 1
J 0
(-7775 6275);
DISPLAY 1.021277 (-7775 6275);
DISPLAY INVISIBLE (-7775 6275);
FORCEPROP 1 LASTPIN (-7825 6175) $PN 1
J 0
(-7815 6155);
DISPLAY 0.489362 (-7815 6155);
PAINT MONO (-7815 6155);
FORCEPROP 1 LASTPIN (-7825 5975) $PN 2
J 0
(-7815 5955);
DISPLAY 0.489362 (-7815 5955);
PAINT MONO (-7815 5955);
FORCEPROP 1 LAST MATERIAL X6S
J 0
(-7775 6025);
DISPLAY 0.489362 (-7775 6025);
PAINT SKYBLUE (-7775 6025);
FORCEPROP 1 LAST TOLERANCE 10%
J 0
(-7775 6075);
DISPLAY 0.489362 (-7775 6075);
PAINT SKYBLUE (-7775 6075);
FORCEPROP 1 LAST VALUE 10UF
J 0
(-7775 6175);
DISPLAY 0.489362 (-7775 6175);
PAINT SKYBLUE (-7775 6175);
FORCEPROP 1 LAST PART_NUMBER CH6104KEA00
J 0
(-7775 5925);
DISPLAY 0.489362 (-7775 5925);
PAINT SKYBLUE (-7775 5925);
FORCEPROP 1 LAST VOLTAGE 25V
J 0
(-7775 6125);
DISPLAY 0.489362 (-7775 6125);
PAINT SKYBLUE (-7775 6125);
FORCEPROP 1 LAST PACK_TYPE C0805
J 0
(-7775 5975);
DISPLAY 0.489362 (-7775 5975);
PAINT SKYBLUE (-7775 5975);
FORCEPROP 2 LAST CDS_LIB pure_quanta
J 0
(-7825 6075);
DISPLAY INVISIBLE (-7825 6075);
FORCEPROP 1 LAST PATH I67
J 0
(-7775 6225);
DISPLAY 0.978723 (-7775 6225);
PAINT WHITE (-7775 6225);
DISPLAY INVISIBLE (-7775 6225);
FORCEADD Q_CAP..1
(-7425 6075);
FORCEPROP 1 LAST LOCATION PC628_3
J 0
(-7375 6225);
DISPLAY 0.489362 (-7375 6225);
PAINT SKYBLUE (-7375 6225);
FORCEPROP 0 LAST $SEC 1
J 0
(-7375 6275);
DISPLAY 0.680851 (-7375 6275);
PAINT MONO (-7375 6275);
DISPLAY INVISIBLE (-7375 6275);
FORCEPROP 0 LAST CDS_SEC 1
J 0
(-7375 6275);
DISPLAY 1.021277 (-7375 6275);
DISPLAY INVISIBLE (-7375 6275);
FORCEPROP 1 LASTPIN (-7425 6175) $PN 1
J 0
(-7415 6155);
DISPLAY 0.489362 (-7415 6155);
PAINT MONO (-7415 6155);
FORCEPROP 1 LASTPIN (-7425 5975) $PN 2
J 0
(-7415 5955);
DISPLAY 0.489362 (-7415 5955);
PAINT MONO (-7415 5955);
FORCEPROP 1 LAST MATERIAL X6S
J 0
(-7375 6025);
DISPLAY 0.489362 (-7375 6025);
PAINT SKYBLUE (-7375 6025);
FORCEPROP 1 LAST TOLERANCE 10%
J 0
(-7375 6075);
DISPLAY 0.489362 (-7375 6075);
PAINT SKYBLUE (-7375 6075);
FORCEPROP 1 LAST VALUE 10UF
J 0
(-7375 6175);
DISPLAY 0.489362 (-7375 6175);
PAINT SKYBLUE (-7375 6175);
FORCEPROP 1 LAST PART_NUMBER CH6104KEA00
J 0
(-7375 5925);
DISPLAY 0.489362 (-7375 5925);
PAINT SKYBLUE (-7375 5925);
FORCEPROP 1 LAST VOLTAGE 25V
J 0
(-7375 6125);
DISPLAY 0.489362 (-7375 6125);
PAINT SKYBLUE (-7375 6125);
FORCEPROP 1 LAST PACK_TYPE C0805
J 0
(-7375 5975);
DISPLAY 0.489362 (-7375 5975);
PAINT SKYBLUE (-7375 5975);
FORCEPROP 2 LAST CDS_LIB pure_quanta
J 0
(-7425 6075);
DISPLAY INVISIBLE (-7425 6075);
FORCEPROP 1 LAST PATH I68
J 0
(-7375 6225);
DISPLAY 0.978723 (-7375 6225);
PAINT WHITE (-7375 6225);
DISPLAY INVISIBLE (-7375 6225);
FORCEADD Q_CAP..1
(-7100 5350);
FORCEPROP 1 LAST LOCATION PC631
J 0
(-7050 5450);
DISPLAY 0.489362 (-7050 5450);
PAINT SKYBLUE (-7050 5450);
FORCEPROP 0 LAST $SEC 1
J 0
(-7050 5500);
DISPLAY 0.680851 (-7050 5500);
PAINT MONO (-7050 5500);
DISPLAY INVISIBLE (-7050 5500);
FORCEPROP 0 LAST CDS_SEC 1
J 0
(-7050 5500);
DISPLAY 1.021277 (-7050 5500);
DISPLAY INVISIBLE (-7050 5500);
FORCEPROP 1 LASTPIN (-7100 5450) $PN 1
J 0
(-7090 5430);
DISPLAY 0.489362 (-7090 5430);
PAINT MONO (-7090 5430);
FORCEPROP 1 LASTPIN (-7100 5250) $PN 2
J 0
(-7090 5230);
DISPLAY 0.489362 (-7090 5230);
PAINT MONO (-7090 5230);
FORCEPROP 1 LAST MATERIAL X7R
J 0
(-7050 5250);
DISPLAY 0.489362 (-7050 5250);
PAINT SKYBLUE (-7050 5250);
FORCEPROP 1 LAST TOLERANCE 10%
J 0
(-7050 5300);
DISPLAY 0.489362 (-7050 5300);
PAINT SKYBLUE (-7050 5300);
FORCEPROP 1 LAST VALUE 0.22UF
J 0
(-7050 5400);
DISPLAY 0.489362 (-7050 5400);
PAINT SKYBLUE (-7050 5400);
FORCEPROP 1 LAST PART_NUMBER CH4223K1B00
J 0
(-7050 5200);
DISPLAY 0.489362 (-7050 5200);
PAINT SKYBLUE (-7050 5200);
FORCEPROP 1 LAST VOLTAGE 16V
J 0
(-7050 5350);
DISPLAY 0.489362 (-7050 5350);
PAINT SKYBLUE (-7050 5350);
FORCEPROP 1 LAST PACK_TYPE 0402
J 0
(-7050 5150);
DISPLAY 0.489362 (-7050 5150);
PAINT SKYBLUE (-7050 5150);
FORCEPROP 2 LAST CDS_LIB pure_quanta
J 0
(-7100 5350);
PAINT MONO (-7100 5350);
DISPLAY INVISIBLE (-7100 5350);
FORCEPROP 1 LAST PATH I69
J 0
(-7050 5500);
DISPLAY 0.978723 (-7050 5500);
PAINT WHITE (-7050 5500);
DISPLAY INVISIBLE (-7050 5500);
FORCEADD OFFPAGE..5
(-11050 2325);
FORCEPROP 2 LAST $XR0 193 
J 0
(-11335 2325);
DISPLAY 0.638298 (-11335 2325);
PAINT MONO (-11335 2325);
FORCEPROP 2 LAST PATH I7
J 0
(-11325 2375);
DISPLAY 1.021277 (-11325 2375);
DISPLAY INVISIBLE (-11325 2375);
FORCEPROP 1 LAST COMMENT_BODY TRUE
J 0
(-10950 2250);
DISPLAY 0.872340 (-10950 2250);
PAINT GREEN (-10950 2250);
DISPLAY INVISIBLE (-10950 2250);
FORCEPROP 1 LAST OFFPAGE TRUE
J 0
(-10725 2200);
DISPLAY 0.872340 (-10725 2200);
PAINT GREEN (-10725 2200);
DISPLAY INVISIBLE (-10725 2200);
FORCEPROP 2 LAST CDS_LIB standard
J 0
(-11050 2325);
DISPLAY INVISIBLE (-11050 2325);
FORCEADD UNIVERSAL_GND..1
(-7000 5700);
FORCEPROP 3 LASTPIN (-7000 5750) SIG_NAME GND\g
J 0
(-6990 5760);
DISPLAY 0.659574 (-6990 5760);
PAINT MONO (-6990 5760);
DISPLAY INVISIBLE (-6990 5760);
FORCEPROP 2 LAST CDS_LIB pure_quanta_power
J 0
(-7000 5700);
PAINT MONO (-7000 5700);
DISPLAY INVISIBLE (-7000 5700);
FORCEPROP 1 LAST PATH I70
J 0
(-6925 5700);
DISPLAY 0.872340 (-6925 5700);
PAINT AQUA (-6925 5700);
DISPLAY INVISIBLE (-6925 5700);
FORCEPROP 1 LAST HDL_POWER GND
J 1
(-6975 5625);
DISPLAY 0.872340 (-6975 5625);
PAINT GREEN (-6975 5625);
DISPLAY INVISIBLE (-6975 5625);
FORCEADD Q_CAP..1
(-7000 6100);
FORCEPROP 1 LAST LOCATION PC632_3
J 0
(-6950 6200);
DISPLAY 0.489362 (-6950 6200);
PAINT SKYBLUE (-6950 6200);
FORCEPROP 0 LAST $SEC 1
J 0
(-6950 6250);
DISPLAY 0.680851 (-6950 6250);
PAINT MONO (-6950 6250);
DISPLAY INVISIBLE (-6950 6250);
FORCEPROP 0 LAST CDS_SEC 1
J 0
(-6950 6250);
DISPLAY 1.021277 (-6950 6250);
DISPLAY INVISIBLE (-6950 6250);
FORCEPROP 1 LASTPIN (-7000 6200) $PN 1
J 0
(-6990 6180);
DISPLAY 0.489362 (-6990 6180);
PAINT MONO (-6990 6180);
FORCEPROP 1 LASTPIN (-7000 6000) $PN 2
J 0
(-6990 5980);
DISPLAY 0.489362 (-6990 5980);
PAINT MONO (-6990 5980);
FORCEPROP 1 LAST MATERIAL X6S
J 0
(-6950 6000);
DISPLAY 0.489362 (-6950 6000);
PAINT SKYBLUE (-6950 6000);
FORCEPROP 1 LAST TOLERANCE 10%
J 0
(-6950 6050);
DISPLAY 0.489362 (-6950 6050);
PAINT SKYBLUE (-6950 6050);
FORCEPROP 1 LAST VALUE 10UF
J 0
(-6950 6150);
DISPLAY 0.489362 (-6950 6150);
PAINT SKYBLUE (-6950 6150);
FORCEPROP 1 LAST PART_NUMBER CH6104KEA00
J 0
(-6950 5950);
DISPLAY 0.489362 (-6950 5950);
PAINT SKYBLUE (-6950 5950);
FORCEPROP 1 LAST VOLTAGE 25V
J 0
(-6950 6100);
DISPLAY 0.489362 (-6950 6100);
PAINT SKYBLUE (-6950 6100);
FORCEPROP 1 LAST PACK_TYPE C0805
J 0
(-6950 5900);
DISPLAY 0.489362 (-6950 5900);
PAINT SKYBLUE (-6950 5900);
FORCEPROP 2 LAST CDS_LIB pure_quanta
J 0
(-7000 6100);
DISPLAY INVISIBLE (-7000 6100);
FORCEPROP 1 LAST PATH I71
J 0
(-6950 6250);
DISPLAY 0.978723 (-6950 6250);
PAINT WHITE (-6950 6250);
DISPLAY INVISIBLE (-6950 6250);
FORCEADD VCC_CORE..1
(-7000 6450);
FORCEPROP 3 LASTPIN (-7000 6400) SIG_NAME SW_P12V_STBY_PVDDIO_P1_FLT\g
J 0
(-6990 6410);
DISPLAY 0.659574 (-6990 6410);
PAINT MONO (-6990 6410);
DISPLAY INVISIBLE (-6990 6410);
FORCEPROP 1 LAST HDL_POWER SW_P12V_STBY_PVDDIO_P1_FLT
J 1
(-7000 6500);
DISPLAY 0.489362 (-7000 6500);
PAINT GREEN (-7000 6500);
FORCEPROP 2 LAST CDS_LIB pure_quanta_power
J 0
(-7000 6450);
DISPLAY INVISIBLE (-7000 6450);
FORCEPROP 1 LAST PATH I72
J 0
(-6950 6475);
DISPLAY 0.872340 (-6950 6475);
PAINT AQUA (-6950 6475);
DISPLAY INVISIBLE (-6950 6475);
FORCEADD UNIVERSAL_GND..1
(-4200 1775);
FORCEPROP 3 LASTPIN (-4200 1825) SIG_NAME GND\g
J 0
(-4190 1835);
DISPLAY 0.659574 (-4190 1835);
PAINT MONO (-4190 1835);
DISPLAY INVISIBLE (-4190 1835);
FORCEPROP 2 LAST CDS_LIB pure_quanta_power
J 0
(-4200 1775);
PAINT MONO (-4200 1775);
DISPLAY INVISIBLE (-4200 1775);
FORCEPROP 1 LAST PATH I77
J 0
(-4125 1775);
DISPLAY 0.872340 (-4125 1775);
PAINT AQUA (-4125 1775);
DISPLAY INVISIBLE (-4125 1775);
FORCEPROP 1 LAST HDL_POWER GND
J 1
(-4175 1700);
DISPLAY 0.872340 (-4175 1700);
PAINT GREEN (-4175 1700);
DISPLAY INVISIBLE (-4175 1700);
FORCEADD Q_CAP..1
(-4200 2125);
FORCEPROP 1 LAST LOCATION PC636_4
J 0
(-4150 2250);
DISPLAY 0.489362 (-4150 2250);
PAINT SKYBLUE (-4150 2250);
FORCEPROP 0 LAST $SEC 1
J 0
(-4150 2300);
DISPLAY 0.680851 (-4150 2300);
PAINT MONO (-4150 2300);
DISPLAY INVISIBLE (-4150 2300);
FORCEPROP 0 LAST CDS_SEC 1
J 0
(-4150 2300);
DISPLAY 1.021277 (-4150 2300);
DISPLAY INVISIBLE (-4150 2300);
FORCEPROP 1 LASTPIN (-4200 2225) $PN 1
J 0
(-4190 2205);
DISPLAY 0.489362 (-4190 2205);
PAINT MONO (-4190 2205);
FORCEPROP 1 LASTPIN (-4200 2025) $PN 2
J 0
(-4190 2005);
DISPLAY 0.489362 (-4190 2005);
PAINT MONO (-4190 2005);
FORCEPROP 1 LAST MATERIAL X6S
J 0
(-4150 2050);
DISPLAY 0.489362 (-4150 2050);
PAINT SKYBLUE (-4150 2050);
FORCEPROP 1 LAST TOLERANCE 20%
J 0
(-4150 2100);
DISPLAY 0.489362 (-4150 2100);
PAINT SKYBLUE (-4150 2100);
FORCEPROP 1 LAST VALUE 22UF
J 0
(-4150 2200);
DISPLAY 0.489362 (-4150 2200);
PAINT SKYBLUE (-4150 2200);
FORCEPROP 1 LAST PART_NUMBER TMP_QCH622KMEA01
J 0
(-4150 1950);
DISPLAY 0.489362 (-4150 1950);
PAINT SKYBLUE (-4150 1950);
FORCEPROP 1 LAST VOLTAGE 4V
J 0
(-4150 2150);
DISPLAY 0.489362 (-4150 2150);
PAINT SKYBLUE (-4150 2150);
FORCEPROP 1 LAST PACK_TYPE 0805
J 0
(-4150 2000);
DISPLAY 0.489362 (-4150 2000);
PAINT SKYBLUE (-4150 2000);
FORCEPROP 2 LAST CDS_LIB pure_quanta
J 0
(-4200 2125);
DISPLAY INVISIBLE (-4200 2125);
FORCEPROP 1 LAST PATH I78
J 0
(-4150 2275);
DISPLAY 0.978723 (-4150 2275);
PAINT WHITE (-4150 2275);
DISPLAY INVISIBLE (-4150 2275);
FORCEADD VCC_CORE..1
(-4200 2450);
FORCEPROP 3 LASTPIN (-4200 2400) SIG_NAME PVDDIO_P1\g
J 0
(-4190 2410);
DISPLAY 0.659574 (-4190 2410);
PAINT MONO (-4190 2410);
DISPLAY INVISIBLE (-4190 2410);
FORCEPROP 1 LAST HDL_POWER PVDDIO_P1
J 1
(-4200 2500);
DISPLAY 0.489362 (-4200 2500);
PAINT GREEN (-4200 2500);
FORCEPROP 2 LAST CDS_LIB pure_quanta_power
J 0
(-4200 2450);
DISPLAY INVISIBLE (-4200 2450);
FORCEPROP 1 LAST PATH I79
J 0
(-4150 2475);
DISPLAY 0.872340 (-4150 2475);
PAINT AQUA (-4150 2475);
DISPLAY INVISIBLE (-4150 2475);
FORCEADD Q_CAP..1
(-12075 1950);
FORCEPROP 1 LAST LOCATION PC621_10
J 0
(-12025 2050);
DISPLAY 0.489362 (-12025 2050);
PAINT SKYBLUE (-12025 2050);
FORCEPROP 0 LAST $SEC 1
J 0
(-12025 2075);
DISPLAY 0.680851 (-12025 2075);
PAINT MONO (-12025 2075);
DISPLAY INVISIBLE (-12025 2075);
FORCEPROP 2 LAST CDS_SEC 1
J 0
(-12075 2200);
DISPLAY 1.021277 (-12075 2200);
DISPLAY INVISIBLE (-12075 2200);
FORCEPROP 1 LASTPIN (-12075 2050) $PN 1
J 0
(-12065 2030);
DISPLAY 0.489362 (-12065 2030);
PAINT MONO (-12065 2030);
FORCEPROP 1 LASTPIN (-12075 1850) $PN 2
J 0
(-12065 1830);
DISPLAY 0.489362 (-12065 1830);
PAINT MONO (-12065 1830);
FORCEPROP 1 LAST MATERIAL X7R
J 0
(-12025 1850);
DISPLAY 0.489362 (-12025 1850);
PAINT SKYBLUE (-12025 1850);
FORCEPROP 1 LAST TOLERANCE 10%
J 0
(-12025 1900);
DISPLAY 0.489362 (-12025 1900);
PAINT SKYBLUE (-12025 1900);
FORCEPROP 1 LAST VALUE 0.1UF
J 0
(-12025 2000);
DISPLAY 0.489362 (-12025 2000);
PAINT SKYBLUE (-12025 2000);
FORCEPROP 1 LAST PART_NUMBER CH4104K1B00
J 0
(-12025 1800);
DISPLAY 0.489362 (-12025 1800);
PAINT SKYBLUE (-12025 1800);
FORCEPROP 1 LAST VOLTAGE 25V
J 0
(-12025 1950);
DISPLAY 0.489362 (-12025 1950);
PAINT SKYBLUE (-12025 1950);
FORCEPROP 1 LAST PACK_TYPE 0402
J 0
(-12025 1750);
DISPLAY 0.489362 (-12025 1750);
PAINT SKYBLUE (-12025 1750);
FORCEPROP 2 LAST CDS_LIB pure_quanta
J 0
(-12075 1950);
PAINT MONO (-12075 1950);
DISPLAY INVISIBLE (-12075 1950);
FORCEPROP 1 LAST PATH I8
J 0
(-12025 2100);
DISPLAY 0.978723 (-12025 2100);
PAINT WHITE (-12025 2100);
DISPLAY INVISIBLE (-12025 2100);
FORCEADD Q_CAP..1
(-3875 4925);
FORCEPROP 1 LAST LOCATION PC637_3
J 0
(-3825 5050);
DISPLAY 0.489362 (-3825 5050);
PAINT SKYBLUE (-3825 5050);
FORCEPROP 0 LAST $SEC 1
J 0
(-3825 5100);
DISPLAY 0.680851 (-3825 5100);
PAINT MONO (-3825 5100);
DISPLAY INVISIBLE (-3825 5100);
FORCEPROP 0 LAST CDS_SEC 1
J 0
(-3825 5100);
DISPLAY 1.021277 (-3825 5100);
DISPLAY INVISIBLE (-3825 5100);
FORCEPROP 1 LASTPIN (-3875 5025) $PN 1
J 0
(-3865 5005);
DISPLAY 0.489362 (-3865 5005);
PAINT MONO (-3865 5005);
FORCEPROP 1 LASTPIN (-3875 4825) $PN 2
J 0
(-3865 4805);
DISPLAY 0.489362 (-3865 4805);
PAINT MONO (-3865 4805);
FORCEPROP 1 LAST MATERIAL X6S
J 0
(-3825 4850);
DISPLAY 0.489362 (-3825 4850);
PAINT SKYBLUE (-3825 4850);
FORCEPROP 1 LAST TOLERANCE 20%
J 0
(-3825 4900);
DISPLAY 0.489362 (-3825 4900);
PAINT SKYBLUE (-3825 4900);
FORCEPROP 1 LAST VALUE 22UF
J 0
(-3825 5000);
DISPLAY 0.489362 (-3825 5000);
PAINT SKYBLUE (-3825 5000);
FORCEPROP 1 LAST PART_NUMBER TMP_QCH622KMEA01
J 0
(-3825 4750);
DISPLAY 0.489362 (-3825 4750);
PAINT SKYBLUE (-3825 4750);
FORCEPROP 1 LAST VOLTAGE 4V
J 0
(-3825 4950);
DISPLAY 0.489362 (-3825 4950);
PAINT SKYBLUE (-3825 4950);
FORCEPROP 1 LAST PACK_TYPE 0805
J 0
(-3825 4800);
DISPLAY 0.489362 (-3825 4800);
PAINT SKYBLUE (-3825 4800);
FORCEPROP 2 LAST CDS_LIB pure_quanta
J 0
(-3875 4925);
DISPLAY INVISIBLE (-3875 4925);
FORCEPROP 1 LAST PATH I84
J 0
(-3825 5075);
DISPLAY 0.978723 (-3825 5075);
PAINT WHITE (-3825 5075);
DISPLAY INVISIBLE (-3825 5075);
FORCEADD UNIVERSAL_GND..1
(-3875 4600);
FORCEPROP 3 LASTPIN (-3875 4650) SIG_NAME GND\g
J 0
(-3865 4660);
DISPLAY 0.659574 (-3865 4660);
PAINT MONO (-3865 4660);
DISPLAY INVISIBLE (-3865 4660);
FORCEPROP 2 LAST CDS_LIB pure_quanta_power
J 0
(-3875 4600);
PAINT MONO (-3875 4600);
DISPLAY INVISIBLE (-3875 4600);
FORCEPROP 1 LAST PATH I85
J 0
(-3800 4600);
DISPLAY 0.872340 (-3800 4600);
PAINT AQUA (-3800 4600);
DISPLAY INVISIBLE (-3800 4600);
FORCEPROP 1 LAST HDL_POWER GND
J 1
(-3850 4525);
DISPLAY 0.872340 (-3850 4525);
PAINT GREEN (-3850 4525);
DISPLAY INVISIBLE (-3850 4525);
FORCEADD VCC_CORE..1
(-3875 5250);
FORCEPROP 3 LASTPIN (-3875 5200) SIG_NAME PVDDIO_P1\g
J 0
(-3865 5210);
DISPLAY 0.659574 (-3865 5210);
PAINT MONO (-3865 5210);
DISPLAY INVISIBLE (-3865 5210);
FORCEPROP 1 LAST HDL_POWER PVDDIO_P1
J 1
(-3875 5300);
DISPLAY 0.489362 (-3875 5300);
PAINT GREEN (-3875 5300);
FORCEPROP 2 LAST CDS_LIB pure_quanta_power
J 0
(-3875 5250);
DISPLAY INVISIBLE (-3875 5250);
FORCEPROP 1 LAST PATH I86
J 0
(-3825 5275);
DISPLAY 0.872340 (-3825 5275);
PAINT AQUA (-3825 5275);
DISPLAY INVISIBLE (-3825 5275);
FORCEADD VCC_CORE..1
(-6875 3650);
FORCEPROP 3 LASTPIN (-6875 3600) SIG_NAME SW_P12V_STBY_PVDDIO_P1_FLT\g
J 0
(-6865 3610);
DISPLAY 0.659574 (-6865 3610);
PAINT MONO (-6865 3610);
DISPLAY INVISIBLE (-6865 3610);
FORCEPROP 1 LAST HDL_POWER SW_P12V_STBY_PVDDIO_P1_FLT
J 1
(-6875 3700);
DISPLAY 0.489362 (-6875 3700);
PAINT GREEN (-6875 3700);
FORCEPROP 2 LAST CDS_LIB pure_quanta_power
J 0
(-6875 3650);
DISPLAY INVISIBLE (-6875 3650);
FORCEPROP 1 LAST PATH I87
J 0
(-6825 3675);
DISPLAY 0.872340 (-6825 3675);
PAINT AQUA (-6825 3675);
DISPLAY INVISIBLE (-6825 3675);
FORCEADD OFFPAGE..6
(-7200 4875);
FORCEPROP 2 LAST $XR0 199 
J 0
(-7510 4875);
DISPLAY 0.638298 (-7510 4875);
PAINT MONO (-7510 4875);
FORCEPROP 2 LAST CDS_LIB standard
J 0
(-7200 4875);
DISPLAY INVISIBLE (-7200 4875);
FORCEPROP 1 LAST OFFPAGE TRUE
J 0
(-6875 4750);
DISPLAY 0.872340 (-6875 4750);
PAINT GREEN (-6875 4750);
DISPLAY INVISIBLE (-6875 4750);
FORCEPROP 1 LAST COMMENT_BODY TRUE
J 0
(-7100 4800);
DISPLAY 0.872340 (-7100 4800);
PAINT GREEN (-7100 4800);
DISPLAY INVISIBLE (-7100 4800);
FORCEPROP 2 LAST PATH I89
J 0
(-7150 4950);
DISPLAY 1.021277 (-7150 4950);
DISPLAY INVISIBLE (-7150 4950);
FORCEADD Q_INDUCTOR4P_14..1
(-6175 5000);
FORCEPROP 1 LAST LOCATION PL68
J 0
(-6400 5255);
DISPLAY 0.489362 (-6400 5255);
PAINT SKYBLUE (-6400 5255);
FORCEPROP 0 LAST $SEC 1
J 0
(-6100 5325);
DISPLAY 0.680851 (-6100 5325);
PAINT MONO (-6100 5325);
DISPLAY INVISIBLE (-6100 5325);
FORCEPROP 0 LAST CDS_SEC 1
J 0
(-6100 5325);
DISPLAY 1.021277 (-6100 5325);
DISPLAY INVISIBLE (-6100 5325);
FORCEPROP 0 LASTPIN (-6575 5125) $PN 1
J 2
(-6585 5135);
DISPLAY 0.489362 (-6585 5135);
PAINT MONO (-6585 5135);
FORCEPROP 0 LASTPIN (-6575 4875) $PN 2
J 2
(-6585 4885);
DISPLAY 0.489362 (-6585 4885);
PAINT MONO (-6585 4885);
FORCEPROP 0 LASTPIN (-5775 4875) $PN 3
J 0
(-5765 4885);
DISPLAY 0.489362 (-5765 4885);
PAINT MONO (-5765 4885);
FORCEPROP 0 LASTPIN (-5775 5125) $PN 4
J 0
(-5765 5135);
DISPLAY 0.489362 (-5765 5135);
PAINT MONO (-5765 5135);
FORCEPROP 2 LAST PART_TYPE SMLF
J 0
(-6100 5275);
DISPLAY 1.021277 (-6100 5275);
FORCEPROP 1 LAST MATERIAL IND
J 0
(-6375 5175);
DISPLAY 0.489362 (-6375 5175);
PAINT SKYBLUE (-6375 5175);
FORCEPROP 2 LAST VALUE 150NH
J 0
(-6275 5175);
DISPLAY 0.489362 (-6275 5175);
PAINT SKYBLUE (-6275 5175);
FORCEPROP 1 LAST PART_NUMBER CV+15^0TZ04
J 0
(-6125 5175);
DISPLAY 0.489362 (-6125 5175);
PAINT SKYBLUE (-6125 5175);
FORCEPROP 1 LAST NEEDS_NO_SIZE TRUE
J 0
(-6175 5000);
DISPLAY 0.468085 (-6175 5000);
PAINT GREEN (-6175 5000);
DISPLAY INVISIBLE (-6175 5000);
FORCEPROP 2 LAST CDS_LIB pure_quanta
J 0
(-6175 5000);
DISPLAY INVISIBLE (-6175 5000);
FORCEPROP 1 LAST PATH I93
J 0
(-5975 5155);
DISPLAY 0.723404 (-5975 5155);
PAINT GREEN (-5975 5155);
DISPLAY INVISIBLE (-5975 5155);
FORCEADD Q_CAP..1
(-7175 2550);
FORCEPROP 1 LAST LOCATION PC630
J 0
(-7125 2650);
DISPLAY 0.489362 (-7125 2650);
PAINT SKYBLUE (-7125 2650);
FORCEPROP 0 LAST $SEC 1
J 0
(-7125 2700);
DISPLAY 0.680851 (-7125 2700);
PAINT MONO (-7125 2700);
DISPLAY INVISIBLE (-7125 2700);
FORCEPROP 0 LAST CDS_SEC 1
J 2
(-7125 2675);
DISPLAY 1.021277 (-7125 2675);
DISPLAY INVISIBLE (-7125 2675);
FORCEPROP 1 LASTPIN (-7175 2650) $PN 1
J 0
(-7165 2630);
DISPLAY 0.489362 (-7165 2630);
PAINT MONO (-7165 2630);
FORCEPROP 1 LASTPIN (-7175 2450) $PN 2
J 0
(-7165 2430);
DISPLAY 0.489362 (-7165 2430);
PAINT MONO (-7165 2430);
FORCEPROP 1 LAST MATERIAL X7R
J 0
(-7125 2450);
DISPLAY 0.489362 (-7125 2450);
PAINT SKYBLUE (-7125 2450);
FORCEPROP 1 LAST TOLERANCE 10%
J 0
(-7125 2500);
DISPLAY 0.489362 (-7125 2500);
PAINT SKYBLUE (-7125 2500);
FORCEPROP 1 LAST VALUE 0.22UF
J 0
(-7125 2600);
DISPLAY 0.489362 (-7125 2600);
PAINT SKYBLUE (-7125 2600);
FORCEPROP 1 LAST VOLTAGE 16V
J 0
(-7125 2550);
DISPLAY 0.489362 (-7125 2550);
PAINT SKYBLUE (-7125 2550);
FORCEPROP 1 LAST PART_NUMBER CH4223K1B00
J 0
(-7125 2400);
DISPLAY 0.489362 (-7125 2400);
PAINT SKYBLUE (-7125 2400);
FORCEPROP 1 LAST PACK_TYPE 0402
J 0
(-7125 2350);
DISPLAY 0.489362 (-7125 2350);
PAINT SKYBLUE (-7125 2350);
FORCEPROP 2 LAST CDS_LIB pure_quanta
J 2
(-7175 2550);
DISPLAY INVISIBLE (-7175 2550);
FORCEPROP 1 LAST PATH I94
J 0
(-7125 2700);
DISPLAY 0.978723 (-7125 2700);
PAINT WHITE (-7125 2700);
DISPLAY INVISIBLE (-7125 2700);
FORCEADD Q_RES..1
(-6900 1300);
FORCEPROP 1 LAST LOCATION PR375
J 0
(-6925 1350);
DISPLAY 0.489362 (-6925 1350);
PAINT SKYBLUE (-6925 1350);
FORCEPROP 0 LAST $SEC 1
J 0
(-6650 1425);
DISPLAY 0.680851 (-6650 1425);
PAINT MONO (-6650 1425);
DISPLAY INVISIBLE (-6650 1425);
FORCEPROP 0 LAST CDS_SEC 1
J 0
(-6650 1425);
DISPLAY 1.021277 (-6650 1425);
DISPLAY INVISIBLE (-6650 1425);
FORCEPROP 1 LASTPIN (-7000 1300) $PN 1
J 0
(-6988 1312);
DISPLAY 0.787234 (-6988 1312);
PAINT MONO (-6988 1312);
DISPLAY INVISIBLE (-6988 1312);
FORCEPROP 1 LASTPIN (-6800 1300) $PN 2
J 0
(-6838 1312);
DISPLAY 0.787234 (-6838 1312);
PAINT MONO (-6838 1312);
DISPLAY INVISIBLE (-6838 1312);
FORCEPROP 1 LAST WATTAGE 1/16W
J 2
(-6650 1350);
DISPLAY 0.489362 (-6650 1350);
PAINT SKYBLUE (-6650 1350);
FORCEPROP 1 LAST MATERIAL CHIP
J 0
(-6775 1200);
DISPLAY 0.489362 (-6775 1200);
PAINT SKYBLUE (-6775 1200);
FORCEPROP 1 LAST TOLERANCE 5%
J 0
(-7125 1200);
DISPLAY 0.489362 (-7125 1200);
PAINT SKYBLUE (-7125 1200);
FORCEPROP 1 LAST VALUE 0
J 2
(-7075 1350);
DISPLAY 0.489362 (-7075 1350);
PAINT SKYBLUE (-7075 1350);
FORCEPROP 1 LAST PART_NUMBER CS00002JB38
J 0
(-7225 1250);
DISPLAY 0.489362 (-7225 1250);
PAINT SKYBLUE (-7225 1250);
FORCEPROP 1 LAST PACK_TYPE 0402LF
J 0
(-6800 1250);
DISPLAY 0.489362 (-6800 1250);
PAINT SKYBLUE (-6800 1250);
FORCEPROP 2 LAST CDS_LIB pure_quanta
J 0
(-6900 1300);
DISPLAY INVISIBLE (-6900 1300);
FORCEPROP 1 LAST PATH I95
J 0
(-6950 1450);
DISPLAY 0.978723 (-6950 1450);
PAINT WHITE (-6950 1450);
DISPLAY INVISIBLE (-6950 1450);
FORCEADD Q_CAP..1
(-12050 4750);
FORCEPROP 1 LAST LOCATION PC620_9
J 0
(-12000 4850);
DISPLAY 0.489362 (-12000 4850);
PAINT SKYBLUE (-12000 4850);
FORCEPROP 0 LAST $SEC 1
J 0
(-12000 4875);
DISPLAY 0.680851 (-12000 4875);
PAINT MONO (-12000 4875);
DISPLAY INVISIBLE (-12000 4875);
FORCEPROP 0 LAST CDS_SEC 1
J 0
(-11800 4800);
DISPLAY 1.021277 (-11800 4800);
DISPLAY INVISIBLE (-11800 4800);
FORCEPROP 1 LASTPIN (-12050 4850) $PN 1
J 0
(-12040 4830);
DISPLAY 0.489362 (-12040 4830);
PAINT MONO (-12040 4830);
FORCEPROP 1 LASTPIN (-12050 4650) $PN 2
J 0
(-12040 4630);
DISPLAY 0.489362 (-12040 4630);
PAINT MONO (-12040 4630);
FORCEPROP 1 LAST MATERIAL X7R
J 0
(-12000 4650);
DISPLAY 0.489362 (-12000 4650);
PAINT SKYBLUE (-12000 4650);
FORCEPROP 1 LAST TOLERANCE 10%
J 0
(-12000 4700);
DISPLAY 0.489362 (-12000 4700);
PAINT SKYBLUE (-12000 4700);
FORCEPROP 1 LAST VALUE 0.1UF
J 0
(-12000 4800);
DISPLAY 0.489362 (-12000 4800);
PAINT SKYBLUE (-12000 4800);
FORCEPROP 1 LAST PART_NUMBER CH4104K1B00
J 0
(-12000 4600);
DISPLAY 0.489362 (-12000 4600);
PAINT SKYBLUE (-12000 4600);
FORCEPROP 1 LAST VOLTAGE 25V
J 0
(-12000 4750);
DISPLAY 0.489362 (-12000 4750);
PAINT SKYBLUE (-12000 4750);
FORCEPROP 1 LAST PACK_TYPE 0402
J 0
(-12000 4550);
DISPLAY 0.489362 (-12000 4550);
PAINT SKYBLUE (-12000 4550);
FORCEPROP 2 LAST CDS_LIB pure_quanta
J 0
(-12050 4750);
DISPLAY INVISIBLE (-12050 4750);
FORCEPROP 1 LAST PATH I97
J 0
(-12000 4900);
DISPLAY 0.978723 (-12000 4900);
PAINT WHITE (-12000 4900);
DISPLAY INVISIBLE (-12000 4900);
FORCEADD Q_RES..1
(-8125 5475);
FORCEPROP 1 LAST LOCATION PR373
J 0
(-8175 5525);
DISPLAY 0.489362 (-8175 5525);
PAINT SKYBLUE (-8175 5525);
FORCEPROP 0 LAST $SEC 1
J 0
(-7850 5575);
DISPLAY 0.680851 (-7850 5575);
PAINT MONO (-7850 5575);
DISPLAY INVISIBLE (-7850 5575);
FORCEPROP 0 LAST CDS_SEC 1
J 0
(-7850 5575);
DISPLAY 1.021277 (-7850 5575);
DISPLAY INVISIBLE (-7850 5575);
FORCEPROP 1 LASTPIN (-8225 5475) $PN 1
J 0
(-8213 5487);
DISPLAY 0.787234 (-8213 5487);
PAINT MONO (-8213 5487);
DISPLAY INVISIBLE (-8213 5487);
FORCEPROP 1 LASTPIN (-8025 5475) $PN 2
J 0
(-8063 5487);
DISPLAY 0.787234 (-8063 5487);
PAINT MONO (-8063 5487);
DISPLAY INVISIBLE (-8063 5487);
FORCEPROP 1 LAST PACK_TYPE 0402LF
J 0
(-8025 5375);
DISPLAY 0.489362 (-8025 5375);
PAINT SKYBLUE (-8025 5375);
FORCEPROP 1 LAST TOLERANCE 1%
J 0
(-8300 5375);
DISPLAY 0.489362 (-8300 5375);
PAINT SKYBLUE (-8300 5375);
FORCEPROP 1 LAST MATERIAL CHIP
J 0
(-8025 5425);
DISPLAY 0.489362 (-8025 5425);
PAINT SKYBLUE (-8025 5425);
FORCEPROP 1 LAST WATTAGE 1/16W
J 2
(-7925 5500);
DISPLAY 0.489362 (-7925 5500);
PAINT SKYBLUE (-7925 5500);
FORCEPROP 1 LAST VALUE 4.7
J 2
(-8250 5500);
DISPLAY 0.489362 (-8250 5500);
PAINT SKYBLUE (-8250 5500);
FORCEPROP 1 LAST PART_NUMBER CS-4702FB19
J 0
(-8425 5425);
DISPLAY 0.489362 (-8425 5425);
PAINT SKYBLUE (-8425 5425);
FORCEPROP 1 LAST PATH I98
J 0
(-8175 5625);
DISPLAY 0.978723 (-8175 5625);
PAINT WHITE (-8175 5625);
DISPLAY INVISIBLE (-8175 5625);
FORCEPROP 2 LAST CDS_LIB pure_quanta
J 0
(-8125 5475);
DISPLAY INVISIBLE (-8125 5475);
FORCEADD Q_RES..1
(-8200 2675);
FORCEPROP 1 LAST LOCATION PR372
J 0
(-8225 2725);
DISPLAY 0.489362 (-8225 2725);
PAINT SKYBLUE (-8225 2725);
FORCEPROP 0 LAST $SEC 1
J 0
(-7925 2775);
DISPLAY 0.680851 (-7925 2775);
PAINT MONO (-7925 2775);
DISPLAY INVISIBLE (-7925 2775);
FORCEPROP 0 LAST CDS_SEC 1
J 0
(-7925 2775);
DISPLAY 1.021277 (-7925 2775);
DISPLAY INVISIBLE (-7925 2775);
FORCEPROP 1 LASTPIN (-8300 2675) $PN 1
J 0
(-8288 2687);
DISPLAY 0.787234 (-8288 2687);
PAINT MONO (-8288 2687);
DISPLAY INVISIBLE (-8288 2687);
FORCEPROP 1 LASTPIN (-8100 2675) $PN 2
J 0
(-8138 2687);
DISPLAY 0.787234 (-8138 2687);
PAINT MONO (-8138 2687);
DISPLAY INVISIBLE (-8138 2687);
FORCEPROP 1 LAST PACK_TYPE 0402LF
J 0
(-8125 2575);
DISPLAY 0.489362 (-8125 2575);
PAINT SKYBLUE (-8125 2575);
FORCEPROP 1 LAST TOLERANCE 1%
J 0
(-8375 2575);
DISPLAY 0.489362 (-8375 2575);
PAINT SKYBLUE (-8375 2575);
FORCEPROP 1 LAST MATERIAL CHIP
J 0
(-8100 2625);
DISPLAY 0.489362 (-8100 2625);
PAINT SKYBLUE (-8100 2625);
FORCEPROP 1 LAST WATTAGE 1/16W
J 2
(-7975 2700);
DISPLAY 0.489362 (-7975 2700);
PAINT SKYBLUE (-7975 2700);
FORCEPROP 1 LAST VALUE 4.7
J 2
(-8300 2700);
DISPLAY 0.489362 (-8300 2700);
PAINT SKYBLUE (-8300 2700);
FORCEPROP 1 LAST PART_NUMBER CS-4702FB19
J 0
(-8500 2625);
DISPLAY 0.489362 (-8500 2625);
PAINT SKYBLUE (-8500 2625);
FORCEPROP 1 LAST PATH I99
J 0
(-8250 2825);
DISPLAY 0.978723 (-8250 2825);
PAINT WHITE (-8250 2825);
DISPLAY INVISIBLE (-8250 2825);
FORCEPROP 2 LAST CDS_LIB pure_quanta
J 0
(-8200 2675);
DISPLAY INVISIBLE (-8200 2675);
FORCEADD DNS..1
(-11525 1800);
PAINT RED (-11525 1800);
FORCEPROP 2 LAST CDS_LIB mstr_misc
J 0
(-11525 1800);
PAINT MONO (-11525 1800);
DISPLAY INVISIBLE (-11525 1800);
FORCEPROP 1 LAST COMMENT_BODY TRUE
R 1
J 0
(-11450 1575);
DISPLAY 0.872340 (-11450 1575);
PAINT GREEN (-11450 1575);
DISPLAY INVISIBLE (-11450 1575);
FORCEADD DNS..1
(-11500 4650);
PAINT RED (-11500 4650);
FORCEPROP 2 LAST CDS_LIB mstr_misc
J 0
(-11500 4650);
PAINT MONO (-11500 4650);
DISPLAY INVISIBLE (-11500 4650);
FORCEPROP 1 LAST COMMENT_BODY TRUE
R 1
J 0
(-11425 4425);
DISPLAY 0.872340 (-11425 4425);
PAINT GREEN (-11425 4425);
DISPLAY INVISIBLE (-11425 4425);
FORCEADD DNS..1
(-8100 4425);
PAINT RED (-8100 4425);
FORCEPROP 2 LAST CDS_LIB mstr_misc
J 0
(-8100 4425);
DISPLAY INVISIBLE (-8100 4425);
FORCEPROP 1 LAST COMMENT_BODY TRUE
R 1
J 0
(-8025 4200);
DISPLAY 0.872340 (-8025 4200);
PAINT GREEN (-8025 4200);
DISPLAY INVISIBLE (-8025 4200);
FORCEADD QUANTA_TITLE_BLOCK_C..1
(-3200 375);
FORCEPROP 0 LAST CDS_CON_LAST_MODIFIED Fri Mar 11 14:53:37 2022
J 0
(-5085 390);
DISPLAY INVISIBLE (-5085 390);
FORCEPROP 1 LAST CUSTOM_TXT_CDS <CON_LAST_MODIFIED>
J 0
(-5085 390);
DISPLAY 0.978723 (-5085 390);
FORCEPROP 2 LAST CUSTOM_TXT_CDS <XR_PAGE_TITLE>
J 0
(-11090 5625);
DISPLAY 0.638298 (-11090 5625);
PAINT PINK (-11090 5625);
DISPLAY INVISIBLE (-11090 5625);
FORCEPROP 1 LAST CUSTOM_TXT_CDS <NAME_2>
J 0
(-6375 425);
FORCEPROP 1 LAST CUSTOM_TXT_CDS <NAME_1>
J 0
(-6375 550);
FORCEPROP 1 LAST CUSTOM_TXT_CDS <Q_NUMBER>
J 0
(-4603 478);
DISPLAY 1.212766 (-4603 478);
FORCEPROP 1 LAST CUSTOM_TXT_CDS <Q_PROJ>
J 0
(-5582 477);
DISPLAY 1.212766 (-5582 477);
FORCEPROP 1 LAST CUSTOM_TXT_CDS <Q_REV>
J 0
(-3384 478);
DISPLAY 1.212766 (-3384 478);
FORCEPROP 1 LAST CUSTOM_TXT_CDS <CON_PAGE_NUM> OF <CON_TOTAL_PAGES>
J 0
(-3646 393);
DISPLAY 0.978723 (-3646 393);
FORCEPROP 1 LAST Q_TITLE PVDDIO_P1 VR PHASE 3&4
J 0
(-12500 425);
DISPLAY 2.446809 (-12500 425);
PAINT GREEN (-12500 425);
FORCEPROP 1 LAST Q_DEPT BU9
J 1
(-6963 424);
DISPLAY 1.957447 (-6963 424);
PAINT GREEN (-6963 424);
FORCEPROP 2 LAST PAGE_BORDER TRUE
J 0
(-11090 5625);
DISPLAY 0.638298 (-11090 5625);
PAINT PINK (-11090 5625);
DISPLAY INVISIBLE (-11090 5625);
FORCEPROP 1 LAST CDS_LMAN_SYM_OUTLINE -9475,6775,100,-125
J 0
(-3200 375);
DISPLAY 0.468085 (-3200 375);
PAINT GREEN (-3200 375);
DISPLAY INVISIBLE (-3200 375);
FORCEPROP 2 LAST CDS_LIB pure_quanta
J 0
(-3200 375);
DISPLAY INVISIBLE (-3200 375);
FORCEPROP 1 LAST COMMENT_BODY TRUE
J 0
(-3188 362);
DISPLAY 0.978723 (-3188 362);
PAINT GREEN (-3188 362);
DISPLAY INVISIBLE (-3188 362);
FORCEPROP 2 LAST CDS_XR_PAGE_TITLE CR-199 : @T6G_MB_LIB.T6G(SCH_1):PAGE199
J 0
(-11090 5625);
DISPLAY 0.638298 (-11090 5625);
PAINT PINK (-11090 5625);
DISPLAY INVISIBLE (-11090 5625);
FORCEADD DNS..1
(-8200 2125);
PAINT RED (-8200 2125);
FORCEPROP 2 LAST CDS_LIB mstr_misc
J 0
(-8200 2125);
DISPLAY INVISIBLE (-8200 2125);
FORCEPROP 1 LAST COMMENT_BODY TRUE
R 1
J 0
(-8125 1900);
DISPLAY 0.872340 (-8125 1900);
PAINT GREEN (-8125 1900);
DISPLAY INVISIBLE (-8125 1900);
FORCEADD DNS..1
(-8200 1625);
PAINT RED (-8200 1625);
FORCEPROP 2 LAST CDS_LIB mstr_misc
J 0
(-8200 1625);
DISPLAY INVISIBLE (-8200 1625);
FORCEPROP 1 LAST COMMENT_BODY TRUE
R 1
J 0
(-8125 1400);
DISPLAY 0.872340 (-8125 1400);
PAINT GREEN (-8125 1400);
DISPLAY INVISIBLE (-8125 1400);
FORCEADD DNS..1
(-8100 4925);
PAINT RED (-8100 4925);
FORCEPROP 2 LAST CDS_LIB mstr_misc
J 0
(-8100 4925);
DISPLAY INVISIBLE (-8100 4925);
FORCEPROP 1 LAST COMMENT_BODY TRUE
R 1
J 0
(-8025 4700);
DISPLAY 0.872340 (-8025 4700);
PAINT GREEN (-8025 4700);
DISPLAY INVISIBLE (-8025 4700);
WIRE 16 -1 (-11525 1725)(-11525 1650);
WIRE 16 -1 (-11175 5325)(-11175 5275);
WIRE 16 -1 (-10825 5900)(-10825 5775);
WIRE 16 -1 (-11200 2625)(-11200 2575);
WIRE 16 -1 (-10850 3200)(-10850 3075);
WIRE 16 -1 (-12050 4600)(-12050 4650);
WIRE 16 -1 (-12075 1800)(-12075 1850);
WIRE 16 -1 (-8075 4325)(-8075 4250);
WIRE 16 -1 (-8175 1525)(-8175 1450);
WIRE 16 -1 (-7550 2075)(-7750 2075);
WIRE 16 -1 (-7750 2075)(-7750 2025);
WIRE 16 -1 (-11500 4575)(-11500 4500);
WIRE 16 -1 (-7350 2075)(-6825 2075);
FORCEPROP 2 LAST SIG_NAME IND_PVDDIO_P1_CPL0
J 0
(-7285 2100);
DISPLAY 0.489362 (-7285 2100);
FORCEPROP 2 LASTPROP $XRERR UNIQUE?
J 0
(-7525 2100);
DISPLAY 0.638298 (-7525 2100);
PAINT MONO (-7525 2100);
DISPLAY INVISIBLE (-7525 2100);
WIRE 16 -1 (-9100 2325)(-8175 2325);
FORCEPROP 2 LAST SIG_NAME SW_PVDDIO_P1_SW4
J 0
(-8910 2335);
DISPLAY 0.489362 (-8910 2335);
FORCEPROP 2 LASTPROP $XRERR UNIQUE?
J 0
(-9150 2335);
DISPLAY 0.638298 (-9150 2335);
PAINT MONO (-9150 2335);
DISPLAY INVISIBLE (-9150 2335);
WIRE 16 -1 (-8175 2325)(-6825 2325);
WIRE 16 -1 (-8175 2225)(-8175 2325);
WIRE 16 -1 (-7175 2425)(-7175 2450);
WIRE 16 -1 (-9100 2425)(-7175 2425);
FORCEPROP 2 LAST SIG_NAME SW_PVDDIO_P1_BOOTR4
J 0
(-8910 2435);
DISPLAY 0.489362 (-8910 2435);
FORCEPROP 2 LASTPROP $XRERR UNIQUE?
J 0
(-9150 2435);
DISPLAY 0.638298 (-9150 2435);
PAINT MONO (-9150 2435);
DISPLAY INVISIBLE (-9150 2435);
WIRE 16 -1 (-6875 3375)(-6875 3525);
WIRE 16 -1 (-6875 3600)(-6875 3525);
WIRE 16 -1 (-6875 3525)(-7350 3525);
WIRE 16 -1 (-7350 3375)(-7350 3525);
WIRE 16 -1 (-7750 3525)(-7350 3525);
WIRE 16 -1 (-7750 3525)(-7750 3375);
WIRE 16 -1 (-8150 3525)(-7750 3525);
WIRE 16 -1 (-8150 3375)(-8150 3525);
WIRE 16 -1 (-8625 3525)(-8150 3525);
WIRE 16 -1 (-8625 3400)(-8625 3525);
WIRE 16 -1 (-8925 3525)(-8625 3525);
WIRE 16 -1 (-8925 3525)(-8925 2975);
WIRE 16 -1 (-8925 2975)(-8925 2925);
WIRE 16 -1 (-9100 2975)(-8925 2975);
WIRE 16 -1 (-8925 2925)(-9100 2925);
WIRE 16 -1 (-4675 5125)(-4675 4100);
WIRE 16 -1 (-4675 5125)(-4300 5125);
WIRE 16 -1 (-4675 5125)(-5775 5125);
WIRE 16 -1 (-4675 4100)(-7000 4100);
WIRE 16 -1 (-4300 5125)(-3875 5125);
WIRE 16 -1 (-4300 5125)(-4300 5025);
WIRE 16 -1 (-3875 5200)(-3875 5125);
WIRE 16 -1 (-3875 5025)(-3875 5125);
WIRE 16 -1 (-3875 4700)(-4300 4700);
WIRE 16 -1 (-3875 4650)(-3875 4700);
WIRE 16 -1 (-3875 4825)(-3875 4700);
WIRE 16 -1 (-4300 4700)(-4300 4825);
WIRE 16 -1 (-4200 2225)(-4200 2325);
WIRE 16 -1 (-4200 2400)(-4200 2325);
WIRE 16 -1 (-4625 2325)(-4200 2325);
WIRE 16 -1 (-4625 2225)(-4625 2325);
WIRE 16 -1 (-4625 2325)(-5025 2325);
WIRE 16 -1 (-5025 2325)(-6025 2325);
WIRE 16 -1 (-5025 1300)(-5025 2325);
WIRE 16 -1 (-5025 1300)(-6800 1300);
WIRE 16 -1 (-4200 1900)(-4625 1900);
WIRE 16 -1 (-4200 1825)(-4200 1900);
WIRE 16 -1 (-4200 2025)(-4200 1900);
WIRE 16 -1 (-4625 1900)(-4625 2025);
WIRE 16 -1 (-7000 6400)(-7000 6325);
WIRE 16 -1 (-7000 6325)(-7000 6200);
WIRE 16 -1 (-7000 6325)(-7425 6325);
WIRE 16 -1 (-7425 6175)(-7425 6325);
WIRE 16 -1 (-7825 6325)(-7425 6325);
WIRE 16 -1 (-7825 6325)(-7825 6175);
WIRE 16 -1 (-8225 6325)(-7825 6325);
WIRE 16 -1 (-8225 6175)(-8225 6325);
WIRE 16 -1 (-8650 6325)(-8225 6325);
WIRE 16 -1 (-8650 6175)(-8650 6325);
WIRE 16 -1 (-8925 6325)(-8650 6325);
WIRE 16 -1 (-8925 6325)(-8925 5775);
WIRE 16 -1 (-8925 5775)(-8925 5725);
WIRE 16 -1 (-9100 5775)(-8925 5775);
WIRE 16 -1 (-8925 5725)(-9100 5725);
WIRE 16 -1 (-7000 5750)(-7000 5825);
WIRE 16 -1 (-7000 6000)(-7000 5825);
WIRE 16 -1 (-7000 5825)(-7425 5825);
WIRE 16 -1 (-7425 5975)(-7425 5825);
WIRE 16 -1 (-7825 5825)(-7425 5825);
WIRE 16 -1 (-7825 5975)(-7825 5825);
WIRE 16 -1 (-7825 5825)(-8225 5825);
WIRE 16 -1 (-8225 5975)(-8225 5825);
WIRE 16 -1 (-8650 5825)(-8225 5825);
WIRE 16 -1 (-8650 5975)(-8650 5825);
WIRE 16 -1 (-6875 2950)(-6875 3025);
WIRE 16 -1 (-6875 3175)(-6875 3025);
WIRE 16 -1 (-6875 3025)(-7350 3025);
WIRE 16 -1 (-7350 3175)(-7350 3025);
WIRE 16 -1 (-7750 3025)(-7350 3025);
WIRE 16 -1 (-7750 3175)(-7750 3025);
WIRE 16 -1 (-7750 3025)(-8150 3025);
WIRE 16 -1 (-8150 3175)(-8150 3025);
WIRE 16 -1 (-8625 3025)(-8150 3025);
WIRE 16 -1 (-8625 3200)(-8625 3025);
WIRE 16 -1 (-8850 4625)(-8850 4675);
WIRE 16 -1 (-9100 4625)(-8850 4625);
WIRE 16 -1 (-8850 4625)(-8850 4575);
WIRE 16 -1 (-8850 4675)(-9100 4675);
WIRE 16 -1 (-8850 4575)(-8850 4525);
WIRE 16 -1 (-9100 4575)(-8850 4575);
WIRE 16 -1 (-8850 4525)(-8850 4450);
WIRE 16 -1 (-9100 4525)(-8850 4525);
WIRE 16 -1 (-8850 1825)(-8850 1875);
WIRE 16 -1 (-9100 1825)(-8850 1825);
WIRE 16 -1 (-8850 1825)(-8850 1775);
WIRE 16 -1 (-8850 1875)(-9100 1875);
WIRE 16 -1 (-8850 1775)(-8850 1725);
WIRE 16 -1 (-9100 1775)(-8850 1775);
WIRE 16 -1 (-8850 1725)(-8850 1650);
WIRE 16 -1 (-9100 1725)(-8850 1725);
WIRE 16 -1 (-11200 3375)(-11200 3500);
WIRE 16 -1 (-11200 3625)(-11200 3500);
WIRE 16 -1 (-10850 3500)(-11200 3500);
WIRE 16 -1 (-10850 3500)(-10100 3500);
WIRE 16 -1 (-10850 3400)(-10850 3500);
WIRE 16 -1 (-10100 2975)(-10100 3500);
WIRE 16 -1 (-10100 2975)(-9950 2975);
WIRE 16 -1 (-11175 6075)(-11175 6200);
WIRE 16 -1 (-10825 6200)(-11175 6200);
WIRE 16 -1 (-11175 6325)(-11175 6200);
WIRE 16 -1 (-10825 6100)(-10825 6200);
WIRE 16 -1 (-10500 6200)(-10825 6200);
WIRE 16 -1 (-10500 5775)(-10500 6200);
WIRE 16 -1 (-10500 5775)(-9950 5775);
WIRE 16 -1 (-9100 2675)(-8300 2675);
FORCEPROP 2 LAST SIG_NAME SW_PVDDIO_P1_BOOT4
J 0
(-8885 2685);
DISPLAY 0.489362 (-8885 2685);
FORCEPROP 2 LASTPROP $XRERR UNIQUE?
J 0
(-9125 2685);
DISPLAY 0.638298 (-9125 2685);
PAINT MONO (-9125 2685);
DISPLAY INVISIBLE (-9125 2685);
WIRE 16 -1 (-9100 2075)(-8400 2075);
FORCEPROP 2 LAST SIG_NAME PVDDIO_P1_VOS4
J 0
(-8985 2100);
DISPLAY 0.489362 (-8985 2100);
FORCEPROP 2 LASTPROP $XRERR UNIQUE?
J 0
(-9225 2100);
DISPLAY 0.638298 (-9225 2100);
PAINT MONO (-9225 2100);
DISPLAY INVISIBLE (-9225 2100);
WIRE 16 -1 (-8400 2075)(-8400 1300);
WIRE 16 -1 (-7000 1300)(-8400 1300);
WIRE 16 -1 (-11525 2025)(-9950 2025);
FORCEPROP 2 LAST SIG_NAME PVDDIO_P1_LSET4
J 0
(-10935 2035);
DISPLAY 0.489362 (-10935 2035);
FORCEPROP 2 LASTPROP $XRERR UNIQUE?
J 0
(-11175 2035);
DISPLAY 0.638298 (-11175 2035);
PAINT MONO (-11175 2035);
DISPLAY INVISIBLE (-11175 2035);
WIRE 16 -1 (-11525 2025)(-11525 1925);
WIRE 16 -1 (-9100 5225)(-7100 5225);
FORCEPROP 2 LAST SIG_NAME SW_PVDDIO_P1_BOOTR3
J 0
(-8910 5235);
DISPLAY 0.489362 (-8910 5235);
FORCEPROP 2 LASTPROP $XRERR UNIQUE?
J 0
(-9150 5235);
DISPLAY 0.638298 (-9150 5235);
PAINT MONO (-9150 5235);
DISPLAY INVISIBLE (-9150 5235);
WIRE 16 -1 (-7100 5225)(-7100 5250);
WIRE 16 -1 (-9100 5125)(-8075 5125);
FORCEPROP 2 LAST SIG_NAME SW_PVDDIO_P1_SW3
J 0
(-8910 5135);
DISPLAY 0.489362 (-8910 5135);
FORCEPROP 2 LASTPROP $XRERR UNIQUE?
J 0
(-9150 5135);
DISPLAY 0.638298 (-9150 5135);
PAINT MONO (-9150 5135);
DISPLAY INVISIBLE (-9150 5135);
WIRE 16 -1 (-8075 5125)(-6575 5125);
WIRE 16 -1 (-8075 5025)(-8075 5125);
WIRE 16 -1 (-9950 2475)(-10100 2475);
WIRE 16 -1 (-10100 2675)(-10100 2475);
WIRE 16 -1 (-9950 2675)(-10100 2675);
WIRE 16 -1 (-10100 2675)(-10625 2675);
FORCEPROP 0 LAST CDS_PHYS_NET_NAME PVCCFA_EHV_FIVRA_CPU0_VDD2
J 0
(-10510 2715);
PAINT MONO (-10510 2715);
DISPLAY INVISIBLE (-10510 2715);
FORCEPROP 2 LAST SIG_NAME PVDDIO_P1_VCC4
J 0
(-10535 2685);
DISPLAY 0.489362 (-10535 2685);
FORCEPROP 2 LASTPROP $XRERR UNIQUE?
J 0
(-10775 2685);
DISPLAY 0.638298 (-10775 2685);
PAINT MONO (-10775 2685);
DISPLAY INVISIBLE (-10775 2685);
WIRE 16 -1 (-10625 2900)(-10625 2675);
WIRE 16 -1 (-11200 2900)(-10625 2900);
WIRE 16 -1 (-11200 3175)(-11200 2900);
WIRE 16 -1 (-11200 2900)(-11200 2825);
WIRE 16 -1 (-10375 2075)(-9950 2075);
FORCEPROP 2 LAST SIG_NAME NC_PVDDIO_P1_DNC4
J 0
(-10445 2085);
DISPLAY 0.489362 (-10445 2085);
FORCEPROP 2 LASTPROP $XRERR UNIQUE?
J 0
(-10615 2075);
DISPLAY 0.638298 (-10615 2075);
PAINT MONO (-10615 2075);
DISPLAY INVISIBLE (-10615 2075);
WIRE 16 -1 (-10100 2150)(-12075 2150);
WIRE 16 -1 (-10100 2225)(-10100 2150);
FORCEPROP 0 LAST CDS_PHYS_NET_NAME PVCCIN_CPU0_VREF
J 0
(-10100 2175);
PAINT MONO (-10100 2175);
DISPLAY INVISIBLE (-10100 2175);
WIRE 16 -1 (-12075 2150)(-12075 2050);
WIRE 16 -1 (-11000 2225)(-10100 2225);
FORCEPROP 2 LAST SIG_NAME PVDDCR_CPU1_P1_VCCS
J 0
(-10935 2235);
DISPLAY 0.489362 (-10935 2235);
WIRE 16 -1 (-10100 2225)(-9950 2225);
WIRE 16 -1 (-9950 1725)(-11000 1725);
FORCEPROP 2 LAST SIG_NAME PVDDIO_P1_PWM4
J 0
(-10935 1735);
DISPLAY 0.489362 (-10935 1735);
WIRE 16 -1 (-9950 1825)(-11000 1825);
FORCEPROP 2 LAST SIG_NAME PVDDIO_P1_TEMP1
J 0
(-10935 1835);
DISPLAY 0.489362 (-10935 1835);
WIRE 16 -1 (-9950 2325)(-11000 2325);
FORCEPROP 2 LAST SIG_NAME PVDDIO_P1_IMON4
J 0
(-10935 2335);
DISPLAY 0.489362 (-10935 2335);
WIRE 16 -1 (-9100 1975)(-8600 1975);
FORCEPROP 2 LAST SIG_NAME NC_PVDDIO_P1_GL2_4
J 0
(-8985 1985);
DISPLAY 0.489362 (-8985 1985);
FORCEPROP 2 LASTPROP $XRERR UNIQUE?
J 0
(-8570 1975);
DISPLAY 0.638298 (-8570 1975);
PAINT MONO (-8570 1975);
DISPLAY INVISIBLE (-8570 1975);
WIRE 16 -1 (-9100 2025)(-8600 2025);
FORCEPROP 2 LAST SIG_NAME NC_PVDDIO_P1_GL1_4
J 0
(-8985 2035);
DISPLAY 0.489362 (-8985 2035);
FORCEPROP 2 LASTPROP $XRERR UNIQUE?
J 0
(-8570 2025);
DISPLAY 0.638298 (-8570 2025);
PAINT MONO (-8570 2025);
DISPLAY INVISIBLE (-8570 2025);
WIRE 16 -1 (-9950 5275)(-10100 5275);
WIRE 16 -1 (-10100 5475)(-10100 5275);
WIRE 16 -1 (-9950 5475)(-10100 5475);
WIRE 16 -1 (-10100 5475)(-10525 5475);
FORCEPROP 0 LAST CDS_PHYS_NET_NAME PVCCFA_EHV_FIVRA_CPU0_VDD1
J 0
(-10460 5515);
PAINT MONO (-10460 5515);
DISPLAY INVISIBLE (-10460 5515);
FORCEPROP 2 LAST SIG_NAME PVDDIO_P1_VCC3
J 0
(-10485 5485);
DISPLAY 0.489362 (-10485 5485);
FORCEPROP 2 LASTPROP $XRERR UNIQUE?
J 0
(-10725 5485);
DISPLAY 0.638298 (-10725 5485);
PAINT MONO (-10725 5485);
DISPLAY INVISIBLE (-10725 5485);
WIRE 16 -1 (-10525 5475)(-10525 5600);
WIRE 16 -1 (-11175 5600)(-10525 5600);
WIRE 16 -1 (-11175 5875)(-11175 5600);
WIRE 16 -1 (-11175 5600)(-11175 5525);
WIRE 16 -1 (-10375 4875)(-9950 4875);
FORCEPROP 2 LAST SIG_NAME NC_PVDDIO_P1_DNC3
J 0
(-10470 4885);
DISPLAY 0.489362 (-10470 4885);
FORCEPROP 2 LASTPROP $XRERR UNIQUE?
J 0
(-10615 4875);
DISPLAY 0.638298 (-10615 4875);
PAINT MONO (-10615 4875);
DISPLAY INVISIBLE (-10615 4875);
WIRE 16 -1 (-10100 4950)(-12050 4950);
WIRE 16 -1 (-10100 5025)(-10100 4950);
FORCEPROP 0 LAST CDS_PHYS_NET_NAME PVCCIN_CPU0_VREF
J 0
(-10100 4975);
PAINT MONO (-10100 4975);
DISPLAY INVISIBLE (-10100 4975);
WIRE 16 -1 (-12050 4950)(-12050 4850);
WIRE 16 -1 (-10975 5025)(-10100 5025);
FORCEPROP 2 LAST SIG_NAME PVDDCR_CPU1_P1_VCCS
J 0
(-10910 5035);
DISPLAY 0.489362 (-10910 5035);
WIRE 16 -1 (-10100 5025)(-9950 5025);
WIRE 16 -1 (-11500 4825)(-9950 4825);
FORCEPROP 0 LAST CDS_PHYS_NET_NAME PVCCFA_EHV_FIVRA_CPU0_LSET1
J 0
(-10910 4865);
PAINT MONO (-10910 4865);
DISPLAY INVISIBLE (-10910 4865);
FORCEPROP 2 LAST SIG_NAME PVDDIO_P1_LSET3
J 0
(-10910 4835);
DISPLAY 0.489362 (-10910 4835);
FORCEPROP 2 LASTPROP $XRERR UNIQUE?
J 0
(-11150 4835);
DISPLAY 0.638298 (-11150 4835);
PAINT MONO (-11150 4835);
DISPLAY INVISIBLE (-11150 4835);
WIRE 16 -1 (-11500 4825)(-11500 4775);
WIRE 16 -1 (-9950 4525)(-10975 4525);
FORCEPROP 2 LAST SIG_NAME PVDDIO_P1_PWM3
J 0
(-10910 4535);
DISPLAY 0.489362 (-10910 4535);
WIRE 16 -1 (-9950 4625)(-10975 4625);
FORCEPROP 2 LAST SIG_NAME PVDDIO_P1_TEMP1
J 0
(-10910 4635);
DISPLAY 0.489362 (-10910 4635);
WIRE 16 -1 (-9950 5125)(-10975 5125);
FORCEPROP 2 LAST SIG_NAME PVDDIO_P1_IMON3
J 0
(-10910 5135);
DISPLAY 0.489362 (-10910 5135);
WIRE 16 -1 (-8650 4825)(-9100 4825);
FORCEPROP 2 LAST SIG_NAME NC_PVDDIO_P1_GL1_3
J 0
(-9010 4835);
DISPLAY 0.489362 (-9010 4835);
FORCEPROP 2 LASTPROP $XRERR UNIQUE?
J 0
(-8620 4825);
DISPLAY 0.638298 (-8620 4825);
PAINT MONO (-8620 4825);
DISPLAY INVISIBLE (-8620 4825);
WIRE 16 -1 (-8650 4775)(-9100 4775);
FORCEPROP 2 LAST SIG_NAME NC_PVDDIO_P1_GL2_3
J 0
(-9010 4785);
DISPLAY 0.489362 (-9010 4785);
FORCEPROP 2 LASTPROP $XRERR UNIQUE?
J 0
(-8620 4775);
DISPLAY 0.638298 (-8620 4775);
PAINT MONO (-8620 4775);
DISPLAY INVISIBLE (-8620 4775);
WIRE 16 -1 (-9100 4875)(-8375 4875);
FORCEPROP 2 LAST SIG_NAME PVDDIO_P1_VOS3
J 0
(-9010 4900);
DISPLAY 0.489362 (-9010 4900);
FORCEPROP 2 LASTPROP $XRERR UNIQUE?
J 0
(-9250 4900);
DISPLAY 0.638298 (-9250 4900);
PAINT MONO (-9250 4900);
DISPLAY INVISIBLE (-9250 4900);
WIRE 16 -1 (-8375 4875)(-8375 4100);
WIRE 16 -1 (-7200 4100)(-8375 4100);
WIRE 16 -1 (-9100 5475)(-8225 5475);
FORCEPROP 2 LAST SIG_NAME SW_PVDDIO_P1_BOOT3
J 0
(-8910 5510);
DISPLAY 0.489362 (-8910 5510);
FORCEPROP 2 LASTPROP $XRERR UNIQUE?
J 0
(-9150 5510);
DISPLAY 0.638298 (-9150 5510);
PAINT MONO (-9150 5510);
DISPLAY INVISIBLE (-9150 5510);
WIRE 16 -1 (-8175 2025)(-8175 1725);
FORCEPROP 2 LAST SIG_NAME SW_PVDDIO_P1_SW4_RC
J 0
(-8135 1835);
DISPLAY 0.489362 (-8135 1835);
FORCEPROP 2 LASTPROP $XRERR UNIQUE?
J 0
(-8375 1835);
DISPLAY 0.638298 (-8375 1835);
PAINT MONO (-8375 1835);
DISPLAY INVISIBLE (-8375 1835);
WIRE 16 -1 (-8100 2675)(-7175 2675);
FORCEPROP 2 LAST SIG_NAME SW_PVDDIO_P1_BOOT4_R
J 0
(-7810 2685);
DISPLAY 0.489362 (-7810 2685);
FORCEPROP 2 LASTPROP $XRERR UNIQUE?
J 0
(-8050 2685);
DISPLAY 0.638298 (-8050 2685);
PAINT MONO (-8050 2685);
DISPLAY INVISIBLE (-8050 2685);
WIRE 16 -1 (-7175 2675)(-7175 2650);
WIRE 16 -1 (-6025 2075)(-5525 2075);
FORCEPROP 2 LAST SIG_NAME IND_PVDDIO_P1_CPL4
J 0
(-5985 2085);
DISPLAY 0.489362 (-5985 2085);
WIRE 16 -1 (-8075 4825)(-8075 4525);
FORCEPROP 2 LAST SIG_NAME SW_PVDDIO_P1_SW3_RC
J 0
(-8035 4660);
DISPLAY 0.489362 (-8035 4660);
FORCEPROP 2 LASTPROP $XRERR UNIQUE?
J 0
(-8275 4660);
DISPLAY 0.638298 (-8275 4660);
PAINT MONO (-8275 4660);
DISPLAY INVISIBLE (-8275 4660);
WIRE 16 -1 (-6575 4875)(-7150 4875);
FORCEPROP 2 LAST SIG_NAME IND_PVDDIO_P1_CPL4
J 0
(-7035 4885);
DISPLAY 0.489362 (-7035 4885);
WIRE 16 -1 (-8025 5475)(-7100 5475);
FORCEPROP 2 LAST SIG_NAME SW_PVDDIO_P1_BOOT3_R
J 0
(-7535 5485);
DISPLAY 0.489362 (-7535 5485);
FORCEPROP 2 LASTPROP $XRERR UNIQUE?
J 0
(-7775 5485);
DISPLAY 0.638298 (-7775 5485);
PAINT MONO (-7775 5485);
DISPLAY INVISIBLE (-7775 5485);
WIRE 16 -1 (-7100 5475)(-7100 5450);
WIRE 16 -1 (-5775 4875)(-5150 4875);
FORCEPROP 2 LAST SIG_NAME IND_PVDDIO_P1_CPL3
J 0
(-5685 4885);
DISPLAY 0.489362 (-5685 4885);
DOT 1 (-8225 5825);
DOT 1 (-5025 2325);
DOT 1 (-6875 3525);
DOT 1 (-10850 3500);
DOT 1 (-8850 1775);
DOT 1 (-10100 2225);
DOT 1 (-10100 2675);
DOT 1 (-8625 3525);
DOT 1 (-11175 5600);
DOT 1 (-10825 6200);
DOT 1 (-10100 5025);
DOT 1 (-10100 5475);
DOT 1 (-8850 4525);
DOT 1 (-8850 4575);
DOT 1 (-8850 4625);
DOT 1 (-8650 6325);
DOT 1 (-8225 6325);
DOT 1 (-7750 3025);
DOT 1 (-7350 3025);
DOT 1 (-8150 3525);
DOT 1 (-7350 3525);
DOT 1 (-6875 3025);
DOT 1 (-7825 5825);
DOT 1 (-7000 5825);
DOT 1 (-7825 6325);
DOT 1 (-7425 6325);
DOT 1 (-7000 6325);
DOT 1 (-4300 5125);
DOT 1 (-4675 5125);
DOT 1 (-3875 4700);
DOT 1 (-3875 5125);
DOT 1 (-11200 2900);
DOT 1 (-4200 2325);
DOT 1 (-4200 1900);
DOT 1 (-4625 2325);
DOT 1 (-11200 3500);
DOT 1 (-7425 5825);
DOT 1 (-8150 3025);
DOT 1 (-8925 2975);
DOT 1 (-7750 3525);
DOT 1 (-8850 1825);
DOT 1 (-11175 6200);
DOT 1 (-8925 5775);
DOT 1 (-8175 2325);
DOT 1 (-8075 5125);
DOT 1 (-8850 1725);
FORCENOTE
2ND=CV+22Y0EZ01
(-7550 1825) 0;
DISPLAY LEFT (-7550 1825);
DISPLAY 0.638298 (-7550 1825);
PAINT WHITE (-7550 1825);
FORCENOTE
DCR=0.17M OHM
(-7550 1875) 0;
DISPLAY LEFT (-7550 1875);
DISPLAY 0.638298 (-7550 1875);
PAINT WHITE (-7550 1875);
FORCENOTE
6.5*6.5*10.0
(-7550 1925) 0;
DISPLAY LEFT (-7550 1925);
DISPLAY 0.638298 (-7550 1925);
PAINT WHITE (-7550 1925);
FORCENOTE
ISAT:30A@100C
(-7550 1975) 0;
DISPLAY LEFT (-7550 1975);
DISPLAY 0.638298 (-7550 1975);
PAINT WHITE (-7550 1975);
FORCENOTE
HCME656510Q-221QL
(-7550 2025) 0;
DISPLAY LEFT (-7550 2025);
DISPLAY 0.638298 (-7550 2025);
PAINT WHITE (-7550 2025);
FORCENOTE
PVDDIO_P1_PHASE4
(-9800 3400) 0;
DISPLAY LEFT (-9800 3400);
DISPLAY 1.021277 (-9800 3400);
PAINT WHITE (-9800 3400);
FORCENOTE
PVDDIO_P1_PHASE3
(-9800 6250) 0;
DISPLAY LEFT (-9800 6250);
DISPLAY 1.021277 (-9800 6250);
PAINT WHITE (-9800 6250);
FORCENOTE
DCR=2-3,0.27M OHM
(-5775 5250) 0;
DISPLAY LEFT (-5775 5250);
DISPLAY 0.638298 (-5775 5250);
PAINT WHITE (-5775 5250);
FORCENOTE
PGL6303.151HLT
(-5775 5450) 0;
DISPLAY LEFT (-5775 5450);
DISPLAY 0.638298 (-5775 5450);
PAINT WHITE (-5775 5450);
FORCENOTE
11.0*7.5*12.5
(-5775 5350) 0;
DISPLAY LEFT (-5775 5350);
DISPLAY 0.638298 (-5775 5350);
PAINT WHITE (-5775 5350);
FORCENOTE
ISAT:70A@100C
(-5775 5400) 0;
DISPLAY LEFT (-5775 5400);
DISPLAY 0.638298 (-5775 5400);
PAINT WHITE (-5775 5400);
FORCENOTE
DCR=1-4,0.105M OHM
(-5775 5300) 0;
DISPLAY LEFT (-5775 5300);
DISPLAY 0.638298 (-5775 5300);
PAINT WHITE (-5775 5300);
FORCENOTE
2ND=CV+15^0TZ01
(-5775 5200) 0;
DISPLAY LEFT (-5775 5200);
DISPLAY 0.638298 (-5775 5200);
PAINT WHITE (-5775 5200);
FORCENOTE
PGL6303.151HLT
(-6025 2650) 0;
DISPLAY LEFT (-6025 2650);
DISPLAY 0.638298 (-6025 2650);
PAINT WHITE (-6025 2650);
FORCENOTE
11.0*7.5*12.5
(-6025 2550) 0;
DISPLAY LEFT (-6025 2550);
DISPLAY 0.638298 (-6025 2550);
PAINT WHITE (-6025 2550);
FORCENOTE
ISAT:70A@100C
(-6025 2600) 0;
DISPLAY LEFT (-6025 2600);
DISPLAY 0.638298 (-6025 2600);
PAINT WHITE (-6025 2600);
FORCENOTE
DCR=1-4,0.105M OHM
(-6025 2500) 0;
DISPLAY LEFT (-6025 2500);
DISPLAY 0.638298 (-6025 2500);
PAINT WHITE (-6025 2500);
FORCENOTE
DCR=2-3,0.27M OHM
(-6025 2450) 0;
DISPLAY LEFT (-6025 2450);
DISPLAY 0.638298 (-6025 2450);
PAINT WHITE (-6025 2450);
FORCENOTE
2ND=CV+15^0TZ01
(-6025 2400) 0;
DISPLAY LEFT (-6025 2400);
DISPLAY 0.638298 (-6025 2400);
PAINT WHITE (-6025 2400);
QUIT
